FILE_TYPE = MACRO_DRAWING;
SET COLOR_WIRE YELLOW;
SET COLOR_PROP MONO;
SET COLOR_DOT WHITE;
SET COLOR_ARC YELLOW;
SET COLOR_BODY GREEN;
SET COLOR_NOTE MONO;
SET PROP_DISPLAY VALUE;
SET PAGE_NUMBER P66;
FORCEADD TAP..1
R 2
(-5550 1625);
FORCEPROP 3 LASTPIN (-5500 1625) SIG_NAME P3E_CPU1_PE3_MP_RXN<0>
J 0
(-5490 1635);
DISPLAY 0.659574 (-5490 1635);
PAINT MONO (-5490 1635);
DISPLAY INVISIBLE (-5490 1635);
FORCEPROP 1 LASTPIN (-5500 1625) BN 0
J 2
(-5488 1633);
DISPLAY 0.617021 (-5488 1633);
PAINT GREEN (-5488 1633);
FORCEPROP 2 LAST CDS_LIB mstr_standard
J 0
(-5550 1625);
PAINT MONO (-5550 1625);
DISPLAY INVISIBLE (-5550 1625);
FORCEPROP 1 LAST BODY_TYPE PLUMBING
J 2
(-5550 1675);
DISPLAY 1.446809 (-5550 1675);
PAINT GREEN (-5550 1675);
DISPLAY INVISIBLE (-5550 1675);
FORCEPROP 1 LAST HDL_TAP TRUE
J 2
(-5875 1500);
DISPLAY 1.446809 (-5875 1500);
PAINT GREEN (-5875 1500);
DISPLAY INVISIBLE (-5875 1500);
FORCEPROP 1 LAST PATH I10
J 2
(-5548 1625);
DISPLAY 0.872340 (-5548 1625);
PAINT GREEN (-5548 1625);
DISPLAY INVISIBLE (-5548 1625);
FORCEADD TAP..1
R 2
(-5550 1675);
FORCEPROP 3 LASTPIN (-5500 1675) SIG_NAME P3E_CPU1_PE3_MP_RXN<1>
J 0
(-5490 1685);
DISPLAY 0.659574 (-5490 1685);
PAINT MONO (-5490 1685);
DISPLAY INVISIBLE (-5490 1685);
FORCEPROP 1 LASTPIN (-5500 1675) BN 1
J 2
(-5488 1683);
DISPLAY 0.617021 (-5488 1683);
PAINT GREEN (-5488 1683);
FORCEPROP 2 LAST CDS_LIB mstr_standard
J 0
(-5550 1675);
PAINT MONO (-5550 1675);
DISPLAY INVISIBLE (-5550 1675);
FORCEPROP 1 LAST BODY_TYPE PLUMBING
J 2
(-5550 1725);
DISPLAY 1.446809 (-5550 1725);
PAINT GREEN (-5550 1725);
DISPLAY INVISIBLE (-5550 1725);
FORCEPROP 1 LAST HDL_TAP TRUE
J 2
(-5875 1550);
DISPLAY 1.446809 (-5875 1550);
PAINT GREEN (-5875 1550);
DISPLAY INVISIBLE (-5875 1550);
FORCEPROP 1 LAST PATH I11
J 2
(-5548 1675);
DISPLAY 0.872340 (-5548 1675);
PAINT GREEN (-5548 1675);
DISPLAY INVISIBLE (-5548 1675);
FORCEADD TAP..1
R 2
(-5550 1725);
FORCEPROP 3 LASTPIN (-5500 1725) SIG_NAME P3E_CPU1_PE3_MP_RXN<2>
J 0
(-5490 1735);
DISPLAY 0.659574 (-5490 1735);
PAINT MONO (-5490 1735);
DISPLAY INVISIBLE (-5490 1735);
FORCEPROP 1 LASTPIN (-5500 1725) BN 2
J 2
(-5488 1733);
DISPLAY 0.617021 (-5488 1733);
PAINT GREEN (-5488 1733);
FORCEPROP 2 LAST CDS_LIB mstr_standard
J 0
(-5550 1725);
PAINT MONO (-5550 1725);
DISPLAY INVISIBLE (-5550 1725);
FORCEPROP 1 LAST BODY_TYPE PLUMBING
J 2
(-5550 1775);
DISPLAY 1.446809 (-5550 1775);
PAINT GREEN (-5550 1775);
DISPLAY INVISIBLE (-5550 1775);
FORCEPROP 1 LAST HDL_TAP TRUE
J 2
(-5875 1600);
DISPLAY 1.446809 (-5875 1600);
PAINT GREEN (-5875 1600);
DISPLAY INVISIBLE (-5875 1600);
FORCEPROP 1 LAST PATH I12
J 2
(-5548 1725);
DISPLAY 0.872340 (-5548 1725);
PAINT GREEN (-5548 1725);
DISPLAY INVISIBLE (-5548 1725);
FORCEADD TAP..1
R 2
(-5550 1775);
FORCEPROP 3 LASTPIN (-5500 1775) SIG_NAME P3E_CPU1_PE3_MP_RXN<3>
J 0
(-5490 1785);
DISPLAY 0.659574 (-5490 1785);
PAINT MONO (-5490 1785);
DISPLAY INVISIBLE (-5490 1785);
FORCEPROP 1 LASTPIN (-5500 1775) BN 3
J 2
(-5488 1783);
DISPLAY 0.617021 (-5488 1783);
PAINT GREEN (-5488 1783);
FORCEPROP 2 LAST CDS_LIB mstr_standard
J 0
(-5550 1775);
PAINT MONO (-5550 1775);
DISPLAY INVISIBLE (-5550 1775);
FORCEPROP 1 LAST BODY_TYPE PLUMBING
J 2
(-5550 1825);
DISPLAY 1.446809 (-5550 1825);
PAINT GREEN (-5550 1825);
DISPLAY INVISIBLE (-5550 1825);
FORCEPROP 1 LAST HDL_TAP TRUE
J 2
(-5875 1650);
DISPLAY 1.446809 (-5875 1650);
PAINT GREEN (-5875 1650);
DISPLAY INVISIBLE (-5875 1650);
FORCEPROP 1 LAST PATH I13
J 2
(-5548 1775);
DISPLAY 0.872340 (-5548 1775);
PAINT GREEN (-5548 1775);
DISPLAY INVISIBLE (-5548 1775);
FORCEADD TAP..1
R 2
(-5400 1875);
FORCEPROP 3 LASTPIN (-5350 1875) SIG_NAME P3E_CPU1_PE3_MP_RXP<0>
J 0
(-5340 1885);
DISPLAY 0.659574 (-5340 1885);
PAINT MONO (-5340 1885);
DISPLAY INVISIBLE (-5340 1885);
FORCEPROP 1 LASTPIN (-5350 1875) BN 0
J 2
(-5338 1883);
DISPLAY 0.617021 (-5338 1883);
PAINT GREEN (-5338 1883);
FORCEPROP 2 LAST CDS_LIB mstr_standard
J 0
(-5400 1875);
PAINT MONO (-5400 1875);
DISPLAY INVISIBLE (-5400 1875);
FORCEPROP 1 LAST BODY_TYPE PLUMBING
J 2
(-5400 1925);
DISPLAY 1.446809 (-5400 1925);
PAINT GREEN (-5400 1925);
DISPLAY INVISIBLE (-5400 1925);
FORCEPROP 1 LAST HDL_TAP TRUE
J 2
(-5725 1750);
DISPLAY 1.446809 (-5725 1750);
PAINT GREEN (-5725 1750);
DISPLAY INVISIBLE (-5725 1750);
FORCEPROP 1 LAST PATH I14
J 2
(-5398 1875);
DISPLAY 0.872340 (-5398 1875);
PAINT GREEN (-5398 1875);
DISPLAY INVISIBLE (-5398 1875);
FORCEADD TAP..1
R 2
(-5400 1925);
FORCEPROP 3 LASTPIN (-5350 1925) SIG_NAME P3E_CPU1_PE3_MP_RXP<1>
J 0
(-5340 1935);
DISPLAY 0.659574 (-5340 1935);
PAINT MONO (-5340 1935);
DISPLAY INVISIBLE (-5340 1935);
FORCEPROP 1 LASTPIN (-5350 1925) BN 1
J 2
(-5338 1933);
DISPLAY 0.617021 (-5338 1933);
PAINT GREEN (-5338 1933);
FORCEPROP 2 LAST CDS_LIB mstr_standard
J 0
(-5400 1925);
PAINT MONO (-5400 1925);
DISPLAY INVISIBLE (-5400 1925);
FORCEPROP 1 LAST BODY_TYPE PLUMBING
J 2
(-5400 1975);
DISPLAY 1.446809 (-5400 1975);
PAINT GREEN (-5400 1975);
DISPLAY INVISIBLE (-5400 1975);
FORCEPROP 1 LAST HDL_TAP TRUE
J 2
(-5725 1800);
DISPLAY 1.446809 (-5725 1800);
PAINT GREEN (-5725 1800);
DISPLAY INVISIBLE (-5725 1800);
FORCEPROP 1 LAST PATH I15
J 2
(-5398 1925);
DISPLAY 0.872340 (-5398 1925);
PAINT GREEN (-5398 1925);
DISPLAY INVISIBLE (-5398 1925);
FORCEADD TAP..1
R 2
(-5400 1975);
FORCEPROP 3 LASTPIN (-5350 1975) SIG_NAME P3E_CPU1_PE3_MP_RXP<2>
J 0
(-5340 1985);
DISPLAY 0.659574 (-5340 1985);
PAINT MONO (-5340 1985);
DISPLAY INVISIBLE (-5340 1985);
FORCEPROP 1 LASTPIN (-5350 1975) BN 2
J 2
(-5338 1983);
DISPLAY 0.617021 (-5338 1983);
PAINT GREEN (-5338 1983);
FORCEPROP 2 LAST CDS_LIB mstr_standard
J 0
(-5400 1975);
PAINT MONO (-5400 1975);
DISPLAY INVISIBLE (-5400 1975);
FORCEPROP 1 LAST BODY_TYPE PLUMBING
J 2
(-5400 2025);
DISPLAY 1.446809 (-5400 2025);
PAINT GREEN (-5400 2025);
DISPLAY INVISIBLE (-5400 2025);
FORCEPROP 1 LAST HDL_TAP TRUE
J 2
(-5725 1850);
DISPLAY 1.446809 (-5725 1850);
PAINT GREEN (-5725 1850);
DISPLAY INVISIBLE (-5725 1850);
FORCEPROP 1 LAST PATH I16
J 2
(-5398 1975);
DISPLAY 0.872340 (-5398 1975);
PAINT GREEN (-5398 1975);
DISPLAY INVISIBLE (-5398 1975);
FORCEADD TAP..1
R 2
(-5400 2025);
FORCEPROP 3 LASTPIN (-5350 2025) SIG_NAME P3E_CPU1_PE3_MP_RXP<3>
J 0
(-5340 2035);
DISPLAY 0.659574 (-5340 2035);
PAINT MONO (-5340 2035);
DISPLAY INVISIBLE (-5340 2035);
FORCEPROP 1 LASTPIN (-5350 2025) BN 3
J 2
(-5338 2033);
DISPLAY 0.617021 (-5338 2033);
PAINT GREEN (-5338 2033);
FORCEPROP 2 LAST CDS_LIB mstr_standard
J 0
(-5400 2025);
PAINT MONO (-5400 2025);
DISPLAY INVISIBLE (-5400 2025);
FORCEPROP 1 LAST BODY_TYPE PLUMBING
J 2
(-5400 2075);
DISPLAY 1.446809 (-5400 2075);
PAINT GREEN (-5400 2075);
DISPLAY INVISIBLE (-5400 2075);
FORCEPROP 1 LAST HDL_TAP TRUE
J 2
(-5725 1900);
DISPLAY 1.446809 (-5725 1900);
PAINT GREEN (-5725 1900);
DISPLAY INVISIBLE (-5725 1900);
FORCEPROP 1 LAST PATH I17
J 2
(-5398 2025);
DISPLAY 0.872340 (-5398 2025);
PAINT GREEN (-5398 2025);
DISPLAY INVISIBLE (-5398 2025);
FORCEADD TAP..1
R 2
(-5550 2175);
FORCEPROP 3 LASTPIN (-5500 2175) SIG_NAME P3E_CPU1_PE3_MP_RXN<5>
J 0
(-5490 2185);
DISPLAY 0.659574 (-5490 2185);
PAINT MONO (-5490 2185);
DISPLAY INVISIBLE (-5490 2185);
FORCEPROP 1 LASTPIN (-5500 2175) BN 5
J 2
(-5488 2183);
DISPLAY 0.617021 (-5488 2183);
PAINT GREEN (-5488 2183);
FORCEPROP 2 LAST CDS_LIB mstr_standard
J 0
(-5550 2175);
PAINT MONO (-5550 2175);
DISPLAY INVISIBLE (-5550 2175);
FORCEPROP 1 LAST BODY_TYPE PLUMBING
J 2
(-5550 2225);
DISPLAY 1.446809 (-5550 2225);
PAINT GREEN (-5550 2225);
DISPLAY INVISIBLE (-5550 2225);
FORCEPROP 1 LAST HDL_TAP TRUE
J 2
(-5875 2050);
DISPLAY 1.446809 (-5875 2050);
PAINT GREEN (-5875 2050);
DISPLAY INVISIBLE (-5875 2050);
FORCEPROP 1 LAST PATH I18
J 2
(-5548 2175);
DISPLAY 0.872340 (-5548 2175);
PAINT GREEN (-5548 2175);
DISPLAY INVISIBLE (-5548 2175);
FORCEADD TAP..1
R 2
(-5550 2125);
FORCEPROP 3 LASTPIN (-5500 2125) SIG_NAME P3E_CPU1_PE3_MP_RXN<4>
J 0
(-5490 2135);
DISPLAY 0.659574 (-5490 2135);
PAINT MONO (-5490 2135);
DISPLAY INVISIBLE (-5490 2135);
FORCEPROP 1 LASTPIN (-5500 2125) BN 4
J 2
(-5488 2133);
DISPLAY 0.617021 (-5488 2133);
PAINT GREEN (-5488 2133);
FORCEPROP 2 LAST CDS_LIB mstr_standard
J 0
(-5550 2125);
PAINT MONO (-5550 2125);
DISPLAY INVISIBLE (-5550 2125);
FORCEPROP 1 LAST BODY_TYPE PLUMBING
J 2
(-5550 2175);
DISPLAY 1.446809 (-5550 2175);
PAINT GREEN (-5550 2175);
DISPLAY INVISIBLE (-5550 2175);
FORCEPROP 1 LAST HDL_TAP TRUE
J 2
(-5875 2000);
DISPLAY 1.446809 (-5875 2000);
PAINT GREEN (-5875 2000);
DISPLAY INVISIBLE (-5875 2000);
FORCEPROP 1 LAST PATH I19
J 2
(-5548 2125);
DISPLAY 0.872340 (-5548 2125);
PAINT GREEN (-5548 2125);
DISPLAY INVISIBLE (-5548 2125);
FORCEADD TAP..1
R 2
(-5550 2225);
FORCEPROP 3 LASTPIN (-5500 2225) SIG_NAME P3E_CPU1_PE3_MP_RXN<6>
J 0
(-5490 2235);
DISPLAY 0.659574 (-5490 2235);
PAINT MONO (-5490 2235);
DISPLAY INVISIBLE (-5490 2235);
FORCEPROP 1 LASTPIN (-5500 2225) BN 6
J 2
(-5488 2233);
DISPLAY 0.617021 (-5488 2233);
PAINT GREEN (-5488 2233);
FORCEPROP 2 LAST CDS_LIB mstr_standard
J 0
(-5550 2225);
PAINT MONO (-5550 2225);
DISPLAY INVISIBLE (-5550 2225);
FORCEPROP 1 LAST BODY_TYPE PLUMBING
J 2
(-5550 2275);
DISPLAY 1.446809 (-5550 2275);
PAINT GREEN (-5550 2275);
DISPLAY INVISIBLE (-5550 2275);
FORCEPROP 1 LAST HDL_TAP TRUE
J 2
(-5875 2100);
DISPLAY 1.446809 (-5875 2100);
PAINT GREEN (-5875 2100);
DISPLAY INVISIBLE (-5875 2100);
FORCEPROP 1 LAST PATH I20
J 2
(-5548 2225);
DISPLAY 0.872340 (-5548 2225);
PAINT GREEN (-5548 2225);
DISPLAY INVISIBLE (-5548 2225);
FORCEADD TAP..1
R 2
(-5550 2275);
FORCEPROP 3 LASTPIN (-5500 2275) SIG_NAME P3E_CPU1_PE3_MP_RXN<7>
J 0
(-5490 2285);
DISPLAY 0.659574 (-5490 2285);
PAINT MONO (-5490 2285);
DISPLAY INVISIBLE (-5490 2285);
FORCEPROP 1 LASTPIN (-5500 2275) BN 7
J 2
(-5488 2283);
DISPLAY 0.617021 (-5488 2283);
PAINT GREEN (-5488 2283);
FORCEPROP 2 LAST CDS_LIB mstr_standard
J 0
(-5550 2275);
PAINT MONO (-5550 2275);
DISPLAY INVISIBLE (-5550 2275);
FORCEPROP 1 LAST BODY_TYPE PLUMBING
J 2
(-5550 2325);
DISPLAY 1.446809 (-5550 2325);
PAINT GREEN (-5550 2325);
DISPLAY INVISIBLE (-5550 2325);
FORCEPROP 1 LAST HDL_TAP TRUE
J 2
(-5875 2150);
DISPLAY 1.446809 (-5875 2150);
PAINT GREEN (-5875 2150);
DISPLAY INVISIBLE (-5875 2150);
FORCEPROP 1 LAST PATH I21
J 2
(-5548 2275);
DISPLAY 0.872340 (-5548 2275);
PAINT GREEN (-5548 2275);
DISPLAY INVISIBLE (-5548 2275);
FORCEADD TAP..1
R 2
(-5400 2375);
FORCEPROP 3 LASTPIN (-5350 2375) SIG_NAME P3E_CPU1_PE3_MP_RXP<4>
J 0
(-5340 2385);
DISPLAY 0.659574 (-5340 2385);
PAINT MONO (-5340 2385);
DISPLAY INVISIBLE (-5340 2385);
FORCEPROP 1 LASTPIN (-5350 2375) BN 4
J 2
(-5338 2383);
DISPLAY 0.617021 (-5338 2383);
PAINT GREEN (-5338 2383);
FORCEPROP 2 LAST CDS_LIB mstr_standard
J 0
(-5400 2375);
PAINT MONO (-5400 2375);
DISPLAY INVISIBLE (-5400 2375);
FORCEPROP 1 LAST BODY_TYPE PLUMBING
J 2
(-5400 2425);
DISPLAY 1.446809 (-5400 2425);
PAINT GREEN (-5400 2425);
DISPLAY INVISIBLE (-5400 2425);
FORCEPROP 1 LAST HDL_TAP TRUE
J 2
(-5725 2250);
DISPLAY 1.446809 (-5725 2250);
PAINT GREEN (-5725 2250);
DISPLAY INVISIBLE (-5725 2250);
FORCEPROP 1 LAST PATH I22
J 2
(-5398 2375);
DISPLAY 0.872340 (-5398 2375);
PAINT GREEN (-5398 2375);
DISPLAY INVISIBLE (-5398 2375);
FORCEADD TAP..1
R 2
(-5400 2425);
FORCEPROP 3 LASTPIN (-5350 2425) SIG_NAME P3E_CPU1_PE3_MP_RXP<5>
J 0
(-5340 2435);
DISPLAY 0.659574 (-5340 2435);
PAINT MONO (-5340 2435);
DISPLAY INVISIBLE (-5340 2435);
FORCEPROP 1 LASTPIN (-5350 2425) BN 5
J 2
(-5338 2433);
DISPLAY 0.617021 (-5338 2433);
PAINT GREEN (-5338 2433);
FORCEPROP 2 LAST CDS_LIB mstr_standard
J 0
(-5400 2425);
PAINT MONO (-5400 2425);
DISPLAY INVISIBLE (-5400 2425);
FORCEPROP 1 LAST BODY_TYPE PLUMBING
J 2
(-5400 2475);
DISPLAY 1.446809 (-5400 2475);
PAINT GREEN (-5400 2475);
DISPLAY INVISIBLE (-5400 2475);
FORCEPROP 1 LAST HDL_TAP TRUE
J 2
(-5725 2300);
DISPLAY 1.446809 (-5725 2300);
PAINT GREEN (-5725 2300);
DISPLAY INVISIBLE (-5725 2300);
FORCEPROP 1 LAST PATH I23
J 2
(-5398 2425);
DISPLAY 0.872340 (-5398 2425);
PAINT GREEN (-5398 2425);
DISPLAY INVISIBLE (-5398 2425);
FORCEADD TAP..1
R 2
(-5400 2475);
FORCEPROP 3 LASTPIN (-5350 2475) SIG_NAME P3E_CPU1_PE3_MP_RXP<6>
J 0
(-5340 2485);
DISPLAY 0.659574 (-5340 2485);
PAINT MONO (-5340 2485);
DISPLAY INVISIBLE (-5340 2485);
FORCEPROP 1 LASTPIN (-5350 2475) BN 6
J 2
(-5338 2483);
DISPLAY 0.617021 (-5338 2483);
PAINT GREEN (-5338 2483);
FORCEPROP 2 LAST CDS_LIB mstr_standard
J 0
(-5400 2475);
PAINT MONO (-5400 2475);
DISPLAY INVISIBLE (-5400 2475);
FORCEPROP 1 LAST BODY_TYPE PLUMBING
J 2
(-5400 2525);
DISPLAY 1.446809 (-5400 2525);
PAINT GREEN (-5400 2525);
DISPLAY INVISIBLE (-5400 2525);
FORCEPROP 1 LAST HDL_TAP TRUE
J 2
(-5725 2350);
DISPLAY 1.446809 (-5725 2350);
PAINT GREEN (-5725 2350);
DISPLAY INVISIBLE (-5725 2350);
FORCEPROP 1 LAST PATH I24
J 2
(-5398 2475);
DISPLAY 0.872340 (-5398 2475);
PAINT GREEN (-5398 2475);
DISPLAY INVISIBLE (-5398 2475);
FORCEADD TAP..1
R 2
(-5400 2525);
FORCEPROP 3 LASTPIN (-5350 2525) SIG_NAME P3E_CPU1_PE3_MP_RXP<7>
J 0
(-5340 2535);
DISPLAY 0.659574 (-5340 2535);
PAINT MONO (-5340 2535);
DISPLAY INVISIBLE (-5340 2535);
FORCEPROP 1 LASTPIN (-5350 2525) BN 7
J 2
(-5338 2533);
DISPLAY 0.617021 (-5338 2533);
PAINT GREEN (-5338 2533);
FORCEPROP 2 LAST CDS_LIB mstr_standard
J 0
(-5400 2525);
PAINT MONO (-5400 2525);
DISPLAY INVISIBLE (-5400 2525);
FORCEPROP 1 LAST BODY_TYPE PLUMBING
J 2
(-5400 2575);
DISPLAY 1.446809 (-5400 2575);
PAINT GREEN (-5400 2575);
DISPLAY INVISIBLE (-5400 2575);
FORCEPROP 1 LAST HDL_TAP TRUE
J 2
(-5725 2400);
DISPLAY 1.446809 (-5725 2400);
PAINT GREEN (-5725 2400);
DISPLAY INVISIBLE (-5725 2400);
FORCEPROP 1 LAST PATH I25
J 2
(-5398 2525);
DISPLAY 0.872340 (-5398 2525);
PAINT GREEN (-5398 2525);
DISPLAY INVISIBLE (-5398 2525);
FORCEADD TAP..1
R 2
(-5550 2675);
FORCEPROP 3 LASTPIN (-5500 2675) SIG_NAME P3E_CPU1_PE3_MP_RXN<9>
J 0
(-5490 2685);
DISPLAY 0.659574 (-5490 2685);
PAINT MONO (-5490 2685);
DISPLAY INVISIBLE (-5490 2685);
FORCEPROP 1 LASTPIN (-5500 2675) BN 9
J 2
(-5488 2683);
DISPLAY 0.617021 (-5488 2683);
PAINT GREEN (-5488 2683);
FORCEPROP 2 LAST CDS_LIB mstr_standard
J 0
(-5550 2675);
PAINT MONO (-5550 2675);
DISPLAY INVISIBLE (-5550 2675);
FORCEPROP 1 LAST BODY_TYPE PLUMBING
J 2
(-5550 2725);
DISPLAY 1.446809 (-5550 2725);
PAINT GREEN (-5550 2725);
DISPLAY INVISIBLE (-5550 2725);
FORCEPROP 1 LAST HDL_TAP TRUE
J 2
(-5875 2550);
DISPLAY 1.446809 (-5875 2550);
PAINT GREEN (-5875 2550);
DISPLAY INVISIBLE (-5875 2550);
FORCEPROP 1 LAST PATH I26
J 2
(-5548 2675);
DISPLAY 0.872340 (-5548 2675);
PAINT GREEN (-5548 2675);
DISPLAY INVISIBLE (-5548 2675);
FORCEADD TAP..1
R 2
(-5550 2625);
FORCEPROP 3 LASTPIN (-5500 2625) SIG_NAME P3E_CPU1_PE3_MP_RXN<8>
J 0
(-5490 2635);
DISPLAY 0.659574 (-5490 2635);
PAINT MONO (-5490 2635);
DISPLAY INVISIBLE (-5490 2635);
FORCEPROP 1 LASTPIN (-5500 2625) BN 8
J 2
(-5488 2633);
DISPLAY 0.617021 (-5488 2633);
PAINT GREEN (-5488 2633);
FORCEPROP 2 LAST CDS_LIB mstr_standard
J 0
(-5550 2625);
PAINT MONO (-5550 2625);
DISPLAY INVISIBLE (-5550 2625);
FORCEPROP 1 LAST BODY_TYPE PLUMBING
J 2
(-5550 2675);
DISPLAY 1.446809 (-5550 2675);
PAINT GREEN (-5550 2675);
DISPLAY INVISIBLE (-5550 2675);
FORCEPROP 1 LAST HDL_TAP TRUE
J 2
(-5875 2500);
DISPLAY 1.446809 (-5875 2500);
PAINT GREEN (-5875 2500);
DISPLAY INVISIBLE (-5875 2500);
FORCEPROP 1 LAST PATH I27
J 2
(-5548 2625);
DISPLAY 0.872340 (-5548 2625);
PAINT GREEN (-5548 2625);
DISPLAY INVISIBLE (-5548 2625);
FORCEADD TAP..1
R 2
(-5550 2725);
FORCEPROP 3 LASTPIN (-5500 2725) SIG_NAME P3E_CPU1_PE3_MP_RXN<10>
J 0
(-5490 2735);
DISPLAY 0.659574 (-5490 2735);
PAINT MONO (-5490 2735);
DISPLAY INVISIBLE (-5490 2735);
FORCEPROP 1 LASTPIN (-5500 2725) BN 10
J 2
(-5488 2733);
DISPLAY 0.617021 (-5488 2733);
PAINT GREEN (-5488 2733);
FORCEPROP 2 LAST CDS_LIB mstr_standard
J 0
(-5550 2725);
PAINT MONO (-5550 2725);
DISPLAY INVISIBLE (-5550 2725);
FORCEPROP 1 LAST BODY_TYPE PLUMBING
J 2
(-5550 2775);
DISPLAY 1.446809 (-5550 2775);
PAINT GREEN (-5550 2775);
DISPLAY INVISIBLE (-5550 2775);
FORCEPROP 1 LAST HDL_TAP TRUE
J 2
(-5875 2600);
DISPLAY 1.446809 (-5875 2600);
PAINT GREEN (-5875 2600);
DISPLAY INVISIBLE (-5875 2600);
FORCEPROP 1 LAST PATH I28
J 2
(-5548 2725);
DISPLAY 0.872340 (-5548 2725);
PAINT GREEN (-5548 2725);
DISPLAY INVISIBLE (-5548 2725);
FORCEADD TAP..1
R 2
(-5550 2775);
FORCEPROP 3 LASTPIN (-5500 2775) SIG_NAME P3E_CPU1_PE3_MP_RXN<11>
J 0
(-5490 2785);
DISPLAY 0.659574 (-5490 2785);
PAINT MONO (-5490 2785);
DISPLAY INVISIBLE (-5490 2785);
FORCEPROP 1 LASTPIN (-5500 2775) BN 11
J 2
(-5488 2783);
DISPLAY 0.617021 (-5488 2783);
PAINT GREEN (-5488 2783);
FORCEPROP 2 LAST CDS_LIB mstr_standard
J 0
(-5550 2775);
PAINT MONO (-5550 2775);
DISPLAY INVISIBLE (-5550 2775);
FORCEPROP 1 LAST BODY_TYPE PLUMBING
J 2
(-5550 2825);
DISPLAY 1.446809 (-5550 2825);
PAINT GREEN (-5550 2825);
DISPLAY INVISIBLE (-5550 2825);
FORCEPROP 1 LAST HDL_TAP TRUE
J 2
(-5875 2650);
DISPLAY 1.446809 (-5875 2650);
PAINT GREEN (-5875 2650);
DISPLAY INVISIBLE (-5875 2650);
FORCEPROP 1 LAST PATH I29
J 2
(-5548 2775);
DISPLAY 0.872340 (-5548 2775);
PAINT GREEN (-5548 2775);
DISPLAY INVISIBLE (-5548 2775);
FORCEADD TAP..1
R 2
(-5400 2875);
FORCEPROP 3 LASTPIN (-5350 2875) SIG_NAME P3E_CPU1_PE3_MP_RXP<8>
J 0
(-5340 2885);
DISPLAY 0.659574 (-5340 2885);
PAINT MONO (-5340 2885);
DISPLAY INVISIBLE (-5340 2885);
FORCEPROP 1 LASTPIN (-5350 2875) BN 8
J 2
(-5338 2883);
DISPLAY 0.617021 (-5338 2883);
PAINT GREEN (-5338 2883);
FORCEPROP 2 LAST CDS_LIB mstr_standard
J 0
(-5400 2875);
PAINT MONO (-5400 2875);
DISPLAY INVISIBLE (-5400 2875);
FORCEPROP 1 LAST BODY_TYPE PLUMBING
J 2
(-5400 2925);
DISPLAY 1.446809 (-5400 2925);
PAINT GREEN (-5400 2925);
DISPLAY INVISIBLE (-5400 2925);
FORCEPROP 1 LAST HDL_TAP TRUE
J 2
(-5725 2750);
DISPLAY 1.446809 (-5725 2750);
PAINT GREEN (-5725 2750);
DISPLAY INVISIBLE (-5725 2750);
FORCEPROP 1 LAST PATH I30
J 2
(-5398 2875);
DISPLAY 0.872340 (-5398 2875);
PAINT GREEN (-5398 2875);
DISPLAY INVISIBLE (-5398 2875);
FORCEADD TAP..1
R 2
(-5400 2925);
FORCEPROP 3 LASTPIN (-5350 2925) SIG_NAME P3E_CPU1_PE3_MP_RXP<9>
J 0
(-5340 2935);
DISPLAY 0.659574 (-5340 2935);
PAINT MONO (-5340 2935);
DISPLAY INVISIBLE (-5340 2935);
FORCEPROP 1 LASTPIN (-5350 2925) BN 9
J 2
(-5338 2933);
DISPLAY 0.617021 (-5338 2933);
PAINT GREEN (-5338 2933);
FORCEPROP 2 LAST CDS_LIB mstr_standard
J 0
(-5400 2925);
PAINT MONO (-5400 2925);
DISPLAY INVISIBLE (-5400 2925);
FORCEPROP 1 LAST BODY_TYPE PLUMBING
J 2
(-5400 2975);
DISPLAY 1.446809 (-5400 2975);
PAINT GREEN (-5400 2975);
DISPLAY INVISIBLE (-5400 2975);
FORCEPROP 1 LAST HDL_TAP TRUE
J 2
(-5725 2800);
DISPLAY 1.446809 (-5725 2800);
PAINT GREEN (-5725 2800);
DISPLAY INVISIBLE (-5725 2800);
FORCEPROP 1 LAST PATH I31
J 2
(-5398 2925);
DISPLAY 0.872340 (-5398 2925);
PAINT GREEN (-5398 2925);
DISPLAY INVISIBLE (-5398 2925);
FORCEADD TAP..1
R 2
(-5400 2975);
FORCEPROP 3 LASTPIN (-5350 2975) SIG_NAME P3E_CPU1_PE3_MP_RXP<10>
J 0
(-5340 2985);
DISPLAY 0.659574 (-5340 2985);
PAINT MONO (-5340 2985);
DISPLAY INVISIBLE (-5340 2985);
FORCEPROP 1 LASTPIN (-5350 2975) BN 10
J 2
(-5338 2983);
DISPLAY 0.617021 (-5338 2983);
PAINT GREEN (-5338 2983);
FORCEPROP 2 LAST CDS_LIB mstr_standard
J 0
(-5400 2975);
PAINT MONO (-5400 2975);
DISPLAY INVISIBLE (-5400 2975);
FORCEPROP 1 LAST BODY_TYPE PLUMBING
J 2
(-5400 3025);
DISPLAY 1.446809 (-5400 3025);
PAINT GREEN (-5400 3025);
DISPLAY INVISIBLE (-5400 3025);
FORCEPROP 1 LAST HDL_TAP TRUE
J 2
(-5725 2850);
DISPLAY 1.446809 (-5725 2850);
PAINT GREEN (-5725 2850);
DISPLAY INVISIBLE (-5725 2850);
FORCEPROP 1 LAST PATH I32
J 2
(-5398 2975);
DISPLAY 0.872340 (-5398 2975);
PAINT GREEN (-5398 2975);
DISPLAY INVISIBLE (-5398 2975);
FORCEADD TAP..1
R 2
(-5400 3025);
FORCEPROP 3 LASTPIN (-5350 3025) SIG_NAME P3E_CPU1_PE3_MP_RXP<11>
J 0
(-5340 3035);
DISPLAY 0.659574 (-5340 3035);
PAINT MONO (-5340 3035);
DISPLAY INVISIBLE (-5340 3035);
FORCEPROP 1 LASTPIN (-5350 3025) BN 11
J 2
(-5338 3033);
DISPLAY 0.617021 (-5338 3033);
PAINT GREEN (-5338 3033);
FORCEPROP 2 LAST CDS_LIB mstr_standard
J 0
(-5400 3025);
PAINT MONO (-5400 3025);
DISPLAY INVISIBLE (-5400 3025);
FORCEPROP 1 LAST BODY_TYPE PLUMBING
J 2
(-5400 3075);
DISPLAY 1.446809 (-5400 3075);
PAINT GREEN (-5400 3075);
DISPLAY INVISIBLE (-5400 3075);
FORCEPROP 1 LAST HDL_TAP TRUE
J 2
(-5725 2900);
DISPLAY 1.446809 (-5725 2900);
PAINT GREEN (-5725 2900);
DISPLAY INVISIBLE (-5725 2900);
FORCEPROP 1 LAST PATH I33
J 2
(-5398 3025);
DISPLAY 0.872340 (-5398 3025);
PAINT GREEN (-5398 3025);
DISPLAY INVISIBLE (-5398 3025);
FORCEADD TAP..1
R 2
(-5550 3175);
FORCEPROP 3 LASTPIN (-5500 3175) SIG_NAME P3E_CPU1_PE3_MP_RXN<13>
J 0
(-5490 3185);
DISPLAY 0.659574 (-5490 3185);
PAINT MONO (-5490 3185);
DISPLAY INVISIBLE (-5490 3185);
FORCEPROP 1 LASTPIN (-5500 3175) BN 13
J 2
(-5488 3183);
DISPLAY 0.617021 (-5488 3183);
PAINT GREEN (-5488 3183);
FORCEPROP 2 LAST CDS_LIB mstr_standard
J 0
(-5550 3175);
PAINT MONO (-5550 3175);
DISPLAY INVISIBLE (-5550 3175);
FORCEPROP 1 LAST BODY_TYPE PLUMBING
J 2
(-5550 3225);
DISPLAY 1.446809 (-5550 3225);
PAINT GREEN (-5550 3225);
DISPLAY INVISIBLE (-5550 3225);
FORCEPROP 1 LAST HDL_TAP TRUE
J 2
(-5875 3050);
DISPLAY 1.446809 (-5875 3050);
PAINT GREEN (-5875 3050);
DISPLAY INVISIBLE (-5875 3050);
FORCEPROP 1 LAST PATH I34
J 2
(-5548 3175);
DISPLAY 0.872340 (-5548 3175);
PAINT GREEN (-5548 3175);
DISPLAY INVISIBLE (-5548 3175);
FORCEADD TAP..1
R 2
(-5550 3375);
FORCEPROP 3 LASTPIN (-5500 3375) SIG_NAME P3E_CPU1_PE3_MP_RXN<12>
J 0
(-5490 3385);
DISPLAY 0.659574 (-5490 3385);
PAINT MONO (-5490 3385);
DISPLAY INVISIBLE (-5490 3385);
FORCEPROP 1 LASTPIN (-5500 3375) BN 12
J 2
(-5488 3383);
DISPLAY 0.617021 (-5488 3383);
PAINT GREEN (-5488 3383);
FORCEPROP 2 LAST CDS_LIB mstr_standard
J 0
(-5550 3375);
PAINT MONO (-5550 3375);
DISPLAY INVISIBLE (-5550 3375);
FORCEPROP 1 LAST BODY_TYPE PLUMBING
J 2
(-5550 3425);
DISPLAY 1.446809 (-5550 3425);
PAINT GREEN (-5550 3425);
DISPLAY INVISIBLE (-5550 3425);
FORCEPROP 1 LAST HDL_TAP TRUE
J 2
(-5875 3250);
DISPLAY 1.446809 (-5875 3250);
PAINT GREEN (-5875 3250);
DISPLAY INVISIBLE (-5875 3250);
FORCEPROP 1 LAST PATH I35
J 2
(-5548 3375);
DISPLAY 0.872340 (-5548 3375);
PAINT GREEN (-5548 3375);
DISPLAY INVISIBLE (-5548 3375);
FORCEADD TAP..1
R 2
(-5550 3225);
FORCEPROP 3 LASTPIN (-5500 3225) SIG_NAME P3E_CPU1_PE3_MP_RXN<14>
J 0
(-5490 3235);
DISPLAY 0.659574 (-5490 3235);
PAINT MONO (-5490 3235);
DISPLAY INVISIBLE (-5490 3235);
FORCEPROP 1 LASTPIN (-5500 3225) BN 14
J 2
(-5488 3233);
DISPLAY 0.617021 (-5488 3233);
PAINT GREEN (-5488 3233);
FORCEPROP 2 LAST CDS_LIB mstr_standard
J 0
(-5550 3225);
PAINT MONO (-5550 3225);
DISPLAY INVISIBLE (-5550 3225);
FORCEPROP 1 LAST BODY_TYPE PLUMBING
J 2
(-5550 3275);
DISPLAY 1.446809 (-5550 3275);
PAINT GREEN (-5550 3275);
DISPLAY INVISIBLE (-5550 3275);
FORCEPROP 1 LAST HDL_TAP TRUE
J 2
(-5875 3100);
DISPLAY 1.446809 (-5875 3100);
PAINT GREEN (-5875 3100);
DISPLAY INVISIBLE (-5875 3100);
FORCEPROP 1 LAST PATH I36
J 2
(-5548 3225);
DISPLAY 0.872340 (-5548 3225);
PAINT GREEN (-5548 3225);
DISPLAY INVISIBLE (-5548 3225);
FORCEADD TAP..1
R 2
(-5550 3275);
FORCEPROP 3 LASTPIN (-5500 3275) SIG_NAME P3E_CPU1_PE3_MP_RXN<15>
J 0
(-5490 3285);
DISPLAY 0.659574 (-5490 3285);
PAINT MONO (-5490 3285);
DISPLAY INVISIBLE (-5490 3285);
FORCEPROP 1 LASTPIN (-5500 3275) BN 15
J 2
(-5488 3283);
DISPLAY 0.617021 (-5488 3283);
PAINT GREEN (-5488 3283);
FORCEPROP 2 LAST CDS_LIB mstr_standard
J 0
(-5550 3275);
PAINT MONO (-5550 3275);
DISPLAY INVISIBLE (-5550 3275);
FORCEPROP 1 LAST BODY_TYPE PLUMBING
J 2
(-5550 3325);
DISPLAY 1.446809 (-5550 3325);
PAINT GREEN (-5550 3325);
DISPLAY INVISIBLE (-5550 3325);
FORCEPROP 1 LAST HDL_TAP TRUE
J 2
(-5875 3150);
DISPLAY 1.446809 (-5875 3150);
PAINT GREEN (-5875 3150);
DISPLAY INVISIBLE (-5875 3150);
FORCEPROP 1 LAST PATH I37
J 2
(-5548 3275);
DISPLAY 0.872340 (-5548 3275);
PAINT GREEN (-5548 3275);
DISPLAY INVISIBLE (-5548 3275);
FORCEADD TAP..1
R 2
(-5400 3125);
FORCEPROP 3 LASTPIN (-5350 3125) SIG_NAME P3E_CPU1_PE3_MP_RXP<12>
J 0
(-5340 3135);
DISPLAY 0.659574 (-5340 3135);
PAINT MONO (-5340 3135);
DISPLAY INVISIBLE (-5340 3135);
FORCEPROP 1 LASTPIN (-5350 3125) BN 12
J 2
(-5338 3133);
DISPLAY 0.617021 (-5338 3133);
PAINT GREEN (-5338 3133);
FORCEPROP 2 LAST CDS_LIB mstr_standard
J 0
(-5400 3125);
PAINT MONO (-5400 3125);
DISPLAY INVISIBLE (-5400 3125);
FORCEPROP 1 LAST BODY_TYPE PLUMBING
J 2
(-5400 3175);
DISPLAY 1.446809 (-5400 3175);
PAINT GREEN (-5400 3175);
DISPLAY INVISIBLE (-5400 3175);
FORCEPROP 1 LAST HDL_TAP TRUE
J 2
(-5725 3000);
DISPLAY 1.446809 (-5725 3000);
PAINT GREEN (-5725 3000);
DISPLAY INVISIBLE (-5725 3000);
FORCEPROP 1 LAST PATH I38
J 2
(-5398 3125);
DISPLAY 0.872340 (-5398 3125);
PAINT GREEN (-5398 3125);
DISPLAY INVISIBLE (-5398 3125);
FORCEADD TAP..1
R 2
(-5400 3425);
FORCEPROP 3 LASTPIN (-5350 3425) SIG_NAME P3E_CPU1_PE3_MP_RXP<13>
J 0
(-5340 3435);
DISPLAY 0.659574 (-5340 3435);
PAINT MONO (-5340 3435);
DISPLAY INVISIBLE (-5340 3435);
FORCEPROP 1 LASTPIN (-5350 3425) BN 13
J 2
(-5338 3433);
DISPLAY 0.617021 (-5338 3433);
PAINT GREEN (-5338 3433);
FORCEPROP 2 LAST CDS_LIB mstr_standard
J 0
(-5400 3425);
PAINT MONO (-5400 3425);
DISPLAY INVISIBLE (-5400 3425);
FORCEPROP 1 LAST BODY_TYPE PLUMBING
J 2
(-5400 3475);
DISPLAY 1.446809 (-5400 3475);
PAINT GREEN (-5400 3475);
DISPLAY INVISIBLE (-5400 3475);
FORCEPROP 1 LAST HDL_TAP TRUE
J 2
(-5725 3300);
DISPLAY 1.446809 (-5725 3300);
PAINT GREEN (-5725 3300);
DISPLAY INVISIBLE (-5725 3300);
FORCEPROP 1 LAST PATH I39
J 2
(-5398 3425);
DISPLAY 0.872340 (-5398 3425);
PAINT GREEN (-5398 3425);
DISPLAY INVISIBLE (-5398 3425);
FORCEADD TAP..1
R 2
(-5400 3525);
FORCEPROP 3 LASTPIN (-5350 3525) SIG_NAME P3E_CPU1_PE3_MP_RXP<15>
J 0
(-5340 3535);
DISPLAY 0.659574 (-5340 3535);
PAINT MONO (-5340 3535);
DISPLAY INVISIBLE (-5340 3535);
FORCEPROP 1 LASTPIN (-5350 3525) BN 15
J 2
(-5338 3533);
DISPLAY 0.617021 (-5338 3533);
PAINT GREEN (-5338 3533);
FORCEPROP 2 LAST CDS_LIB mstr_standard
J 0
(-5400 3525);
PAINT MONO (-5400 3525);
DISPLAY INVISIBLE (-5400 3525);
FORCEPROP 1 LAST BODY_TYPE PLUMBING
J 2
(-5400 3575);
DISPLAY 1.446809 (-5400 3575);
PAINT GREEN (-5400 3575);
DISPLAY INVISIBLE (-5400 3575);
FORCEPROP 1 LAST HDL_TAP TRUE
J 2
(-5725 3400);
DISPLAY 1.446809 (-5725 3400);
PAINT GREEN (-5725 3400);
DISPLAY INVISIBLE (-5725 3400);
FORCEPROP 1 LAST PATH I40
J 2
(-5398 3525);
DISPLAY 0.872340 (-5398 3525);
PAINT GREEN (-5398 3525);
DISPLAY INVISIBLE (-5398 3525);
FORCEADD TAP..1
R 2
(-5400 3475);
FORCEPROP 3 LASTPIN (-5350 3475) SIG_NAME P3E_CPU1_PE3_MP_RXP<14>
J 0
(-5340 3485);
DISPLAY 0.659574 (-5340 3485);
PAINT MONO (-5340 3485);
DISPLAY INVISIBLE (-5340 3485);
FORCEPROP 1 LASTPIN (-5350 3475) BN 14
J 2
(-5338 3483);
DISPLAY 0.617021 (-5338 3483);
PAINT GREEN (-5338 3483);
FORCEPROP 2 LAST CDS_LIB mstr_standard
J 0
(-5400 3475);
PAINT MONO (-5400 3475);
DISPLAY INVISIBLE (-5400 3475);
FORCEPROP 1 LAST BODY_TYPE PLUMBING
J 2
(-5400 3525);
DISPLAY 1.446809 (-5400 3525);
PAINT GREEN (-5400 3525);
DISPLAY INVISIBLE (-5400 3525);
FORCEPROP 1 LAST HDL_TAP TRUE
J 2
(-5725 3350);
DISPLAY 1.446809 (-5725 3350);
PAINT GREEN (-5725 3350);
DISPLAY INVISIBLE (-5725 3350);
FORCEPROP 1 LAST PATH I41
J 2
(-5398 3475);
DISPLAY 0.872340 (-5398 3475);
PAINT GREEN (-5398 3475);
DISPLAY INVISIBLE (-5398 3475);
FORCEADD TAP..1
(-2775 1675);
FORCEPROP 3 LASTPIN (-2825 1675) SIG_NAME P3E_CPU1_PE3_MP_TXN<1>
J 0
(-2815 1685);
DISPLAY 0.659574 (-2815 1685);
PAINT MONO (-2815 1685);
DISPLAY INVISIBLE (-2815 1685);
FORCEPROP 1 LASTPIN (-2825 1675) BN 1
J 0
(-2837 1683);
DISPLAY 0.617021 (-2837 1683);
PAINT GREEN (-2837 1683);
FORCEPROP 2 LAST CDS_LIB mstr_standard
J 2
(-2775 1675);
PAINT MONO (-2775 1675);
DISPLAY INVISIBLE (-2775 1675);
FORCEPROP 1 LAST BODY_TYPE PLUMBING
J 0
(-2775 1725);
DISPLAY 1.446809 (-2775 1725);
PAINT GREEN (-2775 1725);
DISPLAY INVISIBLE (-2775 1725);
FORCEPROP 1 LAST HDL_TAP TRUE
J 0
(-2450 1550);
DISPLAY 1.446809 (-2450 1550);
PAINT GREEN (-2450 1550);
DISPLAY INVISIBLE (-2450 1550);
FORCEPROP 1 LAST PATH I42
J 0
(-2777 1675);
DISPLAY 0.872340 (-2777 1675);
PAINT GREEN (-2777 1675);
DISPLAY INVISIBLE (-2777 1675);
FORCEADD TAP..1
(-2775 1625);
FORCEPROP 3 LASTPIN (-2825 1625) SIG_NAME P3E_CPU1_PE3_MP_TXN<0>
J 0
(-2815 1635);
DISPLAY 0.659574 (-2815 1635);
PAINT MONO (-2815 1635);
DISPLAY INVISIBLE (-2815 1635);
FORCEPROP 1 LASTPIN (-2825 1625) BN 0
J 0
(-2837 1633);
DISPLAY 0.617021 (-2837 1633);
PAINT GREEN (-2837 1633);
FORCEPROP 2 LAST CDS_LIB mstr_standard
J 2
(-2775 1625);
PAINT MONO (-2775 1625);
DISPLAY INVISIBLE (-2775 1625);
FORCEPROP 1 LAST BODY_TYPE PLUMBING
J 0
(-2775 1675);
DISPLAY 1.446809 (-2775 1675);
PAINT GREEN (-2775 1675);
DISPLAY INVISIBLE (-2775 1675);
FORCEPROP 1 LAST HDL_TAP TRUE
J 0
(-2450 1500);
DISPLAY 1.446809 (-2450 1500);
PAINT GREEN (-2450 1500);
DISPLAY INVISIBLE (-2450 1500);
FORCEPROP 1 LAST PATH I43
J 0
(-2777 1625);
DISPLAY 0.872340 (-2777 1625);
PAINT GREEN (-2777 1625);
DISPLAY INVISIBLE (-2777 1625);
FORCEADD TAP..1
(-2775 1725);
FORCEPROP 3 LASTPIN (-2825 1725) SIG_NAME P3E_CPU1_PE3_MP_TXN<2>
J 0
(-2815 1735);
DISPLAY 0.659574 (-2815 1735);
PAINT MONO (-2815 1735);
DISPLAY INVISIBLE (-2815 1735);
FORCEPROP 1 LASTPIN (-2825 1725) BN 2
J 0
(-2837 1733);
DISPLAY 0.617021 (-2837 1733);
PAINT GREEN (-2837 1733);
FORCEPROP 2 LAST CDS_LIB mstr_standard
J 2
(-2775 1725);
PAINT MONO (-2775 1725);
DISPLAY INVISIBLE (-2775 1725);
FORCEPROP 1 LAST BODY_TYPE PLUMBING
J 0
(-2775 1775);
DISPLAY 1.446809 (-2775 1775);
PAINT GREEN (-2775 1775);
DISPLAY INVISIBLE (-2775 1775);
FORCEPROP 1 LAST HDL_TAP TRUE
J 0
(-2450 1600);
DISPLAY 1.446809 (-2450 1600);
PAINT GREEN (-2450 1600);
DISPLAY INVISIBLE (-2450 1600);
FORCEPROP 1 LAST PATH I44
J 0
(-2777 1725);
DISPLAY 0.872340 (-2777 1725);
PAINT GREEN (-2777 1725);
DISPLAY INVISIBLE (-2777 1725);
FORCEADD TAP..1
(-2775 1775);
FORCEPROP 3 LASTPIN (-2825 1775) SIG_NAME P3E_CPU1_PE3_MP_TXN<3>
J 0
(-2815 1785);
DISPLAY 0.659574 (-2815 1785);
PAINT MONO (-2815 1785);
DISPLAY INVISIBLE (-2815 1785);
FORCEPROP 1 LASTPIN (-2825 1775) BN 3
J 0
(-2837 1783);
DISPLAY 0.617021 (-2837 1783);
PAINT GREEN (-2837 1783);
FORCEPROP 2 LAST CDS_LIB mstr_standard
J 2
(-2775 1775);
PAINT MONO (-2775 1775);
DISPLAY INVISIBLE (-2775 1775);
FORCEPROP 1 LAST BODY_TYPE PLUMBING
J 0
(-2775 1825);
DISPLAY 1.446809 (-2775 1825);
PAINT GREEN (-2775 1825);
DISPLAY INVISIBLE (-2775 1825);
FORCEPROP 1 LAST HDL_TAP TRUE
J 0
(-2450 1650);
DISPLAY 1.446809 (-2450 1650);
PAINT GREEN (-2450 1650);
DISPLAY INVISIBLE (-2450 1650);
FORCEPROP 1 LAST PATH I45
J 0
(-2777 1775);
DISPLAY 0.872340 (-2777 1775);
PAINT GREEN (-2777 1775);
DISPLAY INVISIBLE (-2777 1775);
FORCEADD TAP..1
(-2925 1875);
FORCEPROP 3 LASTPIN (-2975 1875) SIG_NAME P3E_CPU1_PE3_MP_TXP<0>
J 0
(-2965 1885);
DISPLAY 0.659574 (-2965 1885);
PAINT MONO (-2965 1885);
DISPLAY INVISIBLE (-2965 1885);
FORCEPROP 1 LASTPIN (-2975 1875) BN 0
J 0
(-2987 1883);
DISPLAY 0.617021 (-2987 1883);
PAINT GREEN (-2987 1883);
FORCEPROP 2 LAST CDS_LIB mstr_standard
J 2
(-2925 1875);
PAINT MONO (-2925 1875);
DISPLAY INVISIBLE (-2925 1875);
FORCEPROP 1 LAST BODY_TYPE PLUMBING
J 0
(-2925 1925);
DISPLAY 1.446809 (-2925 1925);
PAINT GREEN (-2925 1925);
DISPLAY INVISIBLE (-2925 1925);
FORCEPROP 1 LAST HDL_TAP TRUE
J 0
(-2600 1750);
DISPLAY 1.446809 (-2600 1750);
PAINT GREEN (-2600 1750);
DISPLAY INVISIBLE (-2600 1750);
FORCEPROP 1 LAST PATH I46
J 0
(-2927 1875);
DISPLAY 0.872340 (-2927 1875);
PAINT GREEN (-2927 1875);
DISPLAY INVISIBLE (-2927 1875);
FORCEADD TAP..1
(-2925 1975);
FORCEPROP 3 LASTPIN (-2975 1975) SIG_NAME P3E_CPU1_PE3_MP_TXP<2>
J 0
(-2965 1985);
DISPLAY 0.659574 (-2965 1985);
PAINT MONO (-2965 1985);
DISPLAY INVISIBLE (-2965 1985);
FORCEPROP 1 LASTPIN (-2975 1975) BN 2
J 0
(-2987 1983);
DISPLAY 0.617021 (-2987 1983);
PAINT GREEN (-2987 1983);
FORCEPROP 2 LAST CDS_LIB mstr_standard
J 2
(-2925 1975);
PAINT MONO (-2925 1975);
DISPLAY INVISIBLE (-2925 1975);
FORCEPROP 1 LAST BODY_TYPE PLUMBING
J 0
(-2925 2025);
DISPLAY 1.446809 (-2925 2025);
PAINT GREEN (-2925 2025);
DISPLAY INVISIBLE (-2925 2025);
FORCEPROP 1 LAST HDL_TAP TRUE
J 0
(-2600 1850);
DISPLAY 1.446809 (-2600 1850);
PAINT GREEN (-2600 1850);
DISPLAY INVISIBLE (-2600 1850);
FORCEPROP 1 LAST PATH I47
J 0
(-2927 1975);
DISPLAY 0.872340 (-2927 1975);
PAINT GREEN (-2927 1975);
DISPLAY INVISIBLE (-2927 1975);
FORCEADD TAP..1
(-2925 1925);
FORCEPROP 3 LASTPIN (-2975 1925) SIG_NAME P3E_CPU1_PE3_MP_TXP<1>
J 0
(-2965 1935);
DISPLAY 0.659574 (-2965 1935);
PAINT MONO (-2965 1935);
DISPLAY INVISIBLE (-2965 1935);
FORCEPROP 1 LASTPIN (-2975 1925) BN 1
J 0
(-2987 1933);
DISPLAY 0.617021 (-2987 1933);
PAINT GREEN (-2987 1933);
FORCEPROP 2 LAST CDS_LIB mstr_standard
J 2
(-2925 1925);
PAINT MONO (-2925 1925);
DISPLAY INVISIBLE (-2925 1925);
FORCEPROP 1 LAST BODY_TYPE PLUMBING
J 0
(-2925 1975);
DISPLAY 1.446809 (-2925 1975);
PAINT GREEN (-2925 1975);
DISPLAY INVISIBLE (-2925 1975);
FORCEPROP 1 LAST HDL_TAP TRUE
J 0
(-2600 1800);
DISPLAY 1.446809 (-2600 1800);
PAINT GREEN (-2600 1800);
DISPLAY INVISIBLE (-2600 1800);
FORCEPROP 1 LAST PATH I48
J 0
(-2927 1925);
DISPLAY 0.872340 (-2927 1925);
PAINT GREEN (-2927 1925);
DISPLAY INVISIBLE (-2927 1925);
FORCEADD TAP..1
(-2925 2025);
FORCEPROP 3 LASTPIN (-2975 2025) SIG_NAME P3E_CPU1_PE3_MP_TXP<3>
J 0
(-2965 2035);
DISPLAY 0.659574 (-2965 2035);
PAINT MONO (-2965 2035);
DISPLAY INVISIBLE (-2965 2035);
FORCEPROP 1 LASTPIN (-2975 2025) BN 3
J 0
(-2987 2033);
DISPLAY 0.617021 (-2987 2033);
PAINT GREEN (-2987 2033);
FORCEPROP 2 LAST CDS_LIB mstr_standard
J 2
(-2925 2025);
PAINT MONO (-2925 2025);
DISPLAY INVISIBLE (-2925 2025);
FORCEPROP 1 LAST BODY_TYPE PLUMBING
J 0
(-2925 2075);
DISPLAY 1.446809 (-2925 2075);
PAINT GREEN (-2925 2075);
DISPLAY INVISIBLE (-2925 2075);
FORCEPROP 1 LAST HDL_TAP TRUE
J 0
(-2600 1900);
DISPLAY 1.446809 (-2600 1900);
PAINT GREEN (-2600 1900);
DISPLAY INVISIBLE (-2600 1900);
FORCEPROP 1 LAST PATH I49
J 0
(-2927 2025);
DISPLAY 0.872340 (-2927 2025);
PAINT GREEN (-2927 2025);
DISPLAY INVISIBLE (-2927 2025);
FORCEADD TAP..1
(-2775 2125);
FORCEPROP 3 LASTPIN (-2825 2125) SIG_NAME P3E_CPU1_PE3_MP_TXN<4>
J 0
(-2815 2135);
DISPLAY 0.659574 (-2815 2135);
PAINT MONO (-2815 2135);
DISPLAY INVISIBLE (-2815 2135);
FORCEPROP 1 LASTPIN (-2825 2125) BN 4
J 0
(-2837 2133);
DISPLAY 0.617021 (-2837 2133);
PAINT GREEN (-2837 2133);
FORCEPROP 2 LAST CDS_LIB mstr_standard
J 2
(-2775 2125);
PAINT MONO (-2775 2125);
DISPLAY INVISIBLE (-2775 2125);
FORCEPROP 1 LAST BODY_TYPE PLUMBING
J 0
(-2775 2175);
DISPLAY 1.446809 (-2775 2175);
PAINT GREEN (-2775 2175);
DISPLAY INVISIBLE (-2775 2175);
FORCEPROP 1 LAST HDL_TAP TRUE
J 0
(-2450 2000);
DISPLAY 1.446809 (-2450 2000);
PAINT GREEN (-2450 2000);
DISPLAY INVISIBLE (-2450 2000);
FORCEPROP 1 LAST PATH I50
J 0
(-2777 2125);
DISPLAY 0.872340 (-2777 2125);
PAINT GREEN (-2777 2125);
DISPLAY INVISIBLE (-2777 2125);
FORCEADD TAP..1
(-2775 2175);
FORCEPROP 3 LASTPIN (-2825 2175) SIG_NAME P3E_CPU1_PE3_MP_TXN<5>
J 0
(-2815 2185);
DISPLAY 0.659574 (-2815 2185);
PAINT MONO (-2815 2185);
DISPLAY INVISIBLE (-2815 2185);
FORCEPROP 1 LASTPIN (-2825 2175) BN 5
J 0
(-2837 2183);
DISPLAY 0.617021 (-2837 2183);
PAINT GREEN (-2837 2183);
FORCEPROP 2 LAST CDS_LIB mstr_standard
J 2
(-2775 2175);
PAINT MONO (-2775 2175);
DISPLAY INVISIBLE (-2775 2175);
FORCEPROP 1 LAST BODY_TYPE PLUMBING
J 0
(-2775 2225);
DISPLAY 1.446809 (-2775 2225);
PAINT GREEN (-2775 2225);
DISPLAY INVISIBLE (-2775 2225);
FORCEPROP 1 LAST HDL_TAP TRUE
J 0
(-2450 2050);
DISPLAY 1.446809 (-2450 2050);
PAINT GREEN (-2450 2050);
DISPLAY INVISIBLE (-2450 2050);
FORCEPROP 1 LAST PATH I51
J 0
(-2777 2175);
DISPLAY 0.872340 (-2777 2175);
PAINT GREEN (-2777 2175);
DISPLAY INVISIBLE (-2777 2175);
FORCEADD TAP..1
(-2775 2225);
FORCEPROP 3 LASTPIN (-2825 2225) SIG_NAME P3E_CPU1_PE3_MP_TXN<6>
J 0
(-2815 2235);
DISPLAY 0.659574 (-2815 2235);
PAINT MONO (-2815 2235);
DISPLAY INVISIBLE (-2815 2235);
FORCEPROP 1 LASTPIN (-2825 2225) BN 6
J 0
(-2837 2233);
DISPLAY 0.617021 (-2837 2233);
PAINT GREEN (-2837 2233);
FORCEPROP 2 LAST CDS_LIB mstr_standard
J 2
(-2775 2225);
PAINT MONO (-2775 2225);
DISPLAY INVISIBLE (-2775 2225);
FORCEPROP 1 LAST BODY_TYPE PLUMBING
J 0
(-2775 2275);
DISPLAY 1.446809 (-2775 2275);
PAINT GREEN (-2775 2275);
DISPLAY INVISIBLE (-2775 2275);
FORCEPROP 1 LAST HDL_TAP TRUE
J 0
(-2450 2100);
DISPLAY 1.446809 (-2450 2100);
PAINT GREEN (-2450 2100);
DISPLAY INVISIBLE (-2450 2100);
FORCEPROP 1 LAST PATH I52
J 0
(-2777 2225);
DISPLAY 0.872340 (-2777 2225);
PAINT GREEN (-2777 2225);
DISPLAY INVISIBLE (-2777 2225);
FORCEADD TAP..1
(-2775 2275);
FORCEPROP 3 LASTPIN (-2825 2275) SIG_NAME P3E_CPU1_PE3_MP_TXN<7>
J 0
(-2815 2285);
DISPLAY 0.659574 (-2815 2285);
PAINT MONO (-2815 2285);
DISPLAY INVISIBLE (-2815 2285);
FORCEPROP 1 LASTPIN (-2825 2275) BN 7
J 0
(-2837 2283);
DISPLAY 0.617021 (-2837 2283);
PAINT GREEN (-2837 2283);
FORCEPROP 2 LAST CDS_LIB mstr_standard
J 2
(-2775 2275);
PAINT MONO (-2775 2275);
DISPLAY INVISIBLE (-2775 2275);
FORCEPROP 1 LAST BODY_TYPE PLUMBING
J 0
(-2775 2325);
DISPLAY 1.446809 (-2775 2325);
PAINT GREEN (-2775 2325);
DISPLAY INVISIBLE (-2775 2325);
FORCEPROP 1 LAST HDL_TAP TRUE
J 0
(-2450 2150);
DISPLAY 1.446809 (-2450 2150);
PAINT GREEN (-2450 2150);
DISPLAY INVISIBLE (-2450 2150);
FORCEPROP 1 LAST PATH I53
J 0
(-2777 2275);
DISPLAY 0.872340 (-2777 2275);
PAINT GREEN (-2777 2275);
DISPLAY INVISIBLE (-2777 2275);
FORCEADD TAP..1
(-2925 2425);
FORCEPROP 3 LASTPIN (-2975 2425) SIG_NAME P3E_CPU1_PE3_MP_TXP<5>
J 0
(-2965 2435);
DISPLAY 0.659574 (-2965 2435);
PAINT MONO (-2965 2435);
DISPLAY INVISIBLE (-2965 2435);
FORCEPROP 1 LASTPIN (-2975 2425) BN 5
J 0
(-2987 2433);
DISPLAY 0.617021 (-2987 2433);
PAINT GREEN (-2987 2433);
FORCEPROP 2 LAST CDS_LIB mstr_standard
J 2
(-2925 2425);
PAINT MONO (-2925 2425);
DISPLAY INVISIBLE (-2925 2425);
FORCEPROP 1 LAST BODY_TYPE PLUMBING
J 0
(-2925 2475);
DISPLAY 1.446809 (-2925 2475);
PAINT GREEN (-2925 2475);
DISPLAY INVISIBLE (-2925 2475);
FORCEPROP 1 LAST HDL_TAP TRUE
J 0
(-2600 2300);
DISPLAY 1.446809 (-2600 2300);
PAINT GREEN (-2600 2300);
DISPLAY INVISIBLE (-2600 2300);
FORCEPROP 1 LAST PATH I54
J 0
(-2927 2425);
DISPLAY 0.872340 (-2927 2425);
PAINT GREEN (-2927 2425);
DISPLAY INVISIBLE (-2927 2425);
FORCEADD TAP..1
(-2925 2375);
FORCEPROP 3 LASTPIN (-2975 2375) SIG_NAME P3E_CPU1_PE3_MP_TXP<4>
J 0
(-2965 2385);
DISPLAY 0.659574 (-2965 2385);
PAINT MONO (-2965 2385);
DISPLAY INVISIBLE (-2965 2385);
FORCEPROP 1 LASTPIN (-2975 2375) BN 4
J 0
(-2987 2383);
DISPLAY 0.617021 (-2987 2383);
PAINT GREEN (-2987 2383);
FORCEPROP 2 LAST CDS_LIB mstr_standard
J 2
(-2925 2375);
PAINT MONO (-2925 2375);
DISPLAY INVISIBLE (-2925 2375);
FORCEPROP 1 LAST BODY_TYPE PLUMBING
J 0
(-2925 2425);
DISPLAY 1.446809 (-2925 2425);
PAINT GREEN (-2925 2425);
DISPLAY INVISIBLE (-2925 2425);
FORCEPROP 1 LAST HDL_TAP TRUE
J 0
(-2600 2250);
DISPLAY 1.446809 (-2600 2250);
PAINT GREEN (-2600 2250);
DISPLAY INVISIBLE (-2600 2250);
FORCEPROP 1 LAST PATH I55
J 0
(-2927 2375);
DISPLAY 0.872340 (-2927 2375);
PAINT GREEN (-2927 2375);
DISPLAY INVISIBLE (-2927 2375);
FORCEADD TAP..1
(-2925 2475);
FORCEPROP 3 LASTPIN (-2975 2475) SIG_NAME P3E_CPU1_PE3_MP_TXP<6>
J 0
(-2965 2485);
DISPLAY 0.659574 (-2965 2485);
PAINT MONO (-2965 2485);
DISPLAY INVISIBLE (-2965 2485);
FORCEPROP 1 LASTPIN (-2975 2475) BN 6
J 0
(-2987 2483);
DISPLAY 0.617021 (-2987 2483);
PAINT GREEN (-2987 2483);
FORCEPROP 2 LAST CDS_LIB mstr_standard
J 2
(-2925 2475);
PAINT MONO (-2925 2475);
DISPLAY INVISIBLE (-2925 2475);
FORCEPROP 1 LAST BODY_TYPE PLUMBING
J 0
(-2925 2525);
DISPLAY 1.446809 (-2925 2525);
PAINT GREEN (-2925 2525);
DISPLAY INVISIBLE (-2925 2525);
FORCEPROP 1 LAST HDL_TAP TRUE
J 0
(-2600 2350);
DISPLAY 1.446809 (-2600 2350);
PAINT GREEN (-2600 2350);
DISPLAY INVISIBLE (-2600 2350);
FORCEPROP 1 LAST PATH I56
J 0
(-2927 2475);
DISPLAY 0.872340 (-2927 2475);
PAINT GREEN (-2927 2475);
DISPLAY INVISIBLE (-2927 2475);
FORCEADD TAP..1
(-2925 2525);
FORCEPROP 3 LASTPIN (-2975 2525) SIG_NAME P3E_CPU1_PE3_MP_TXP<7>
J 0
(-2965 2535);
DISPLAY 0.659574 (-2965 2535);
PAINT MONO (-2965 2535);
DISPLAY INVISIBLE (-2965 2535);
FORCEPROP 1 LASTPIN (-2975 2525) BN 7
J 0
(-2987 2533);
DISPLAY 0.617021 (-2987 2533);
PAINT GREEN (-2987 2533);
FORCEPROP 2 LAST CDS_LIB mstr_standard
J 2
(-2925 2525);
PAINT MONO (-2925 2525);
DISPLAY INVISIBLE (-2925 2525);
FORCEPROP 1 LAST BODY_TYPE PLUMBING
J 0
(-2925 2575);
DISPLAY 1.446809 (-2925 2575);
PAINT GREEN (-2925 2575);
DISPLAY INVISIBLE (-2925 2575);
FORCEPROP 1 LAST HDL_TAP TRUE
J 0
(-2600 2400);
DISPLAY 1.446809 (-2600 2400);
PAINT GREEN (-2600 2400);
DISPLAY INVISIBLE (-2600 2400);
FORCEPROP 1 LAST PATH I57
J 0
(-2927 2525);
DISPLAY 0.872340 (-2927 2525);
PAINT GREEN (-2927 2525);
DISPLAY INVISIBLE (-2927 2525);
FORCEADD TAP..1
(-2775 2625);
FORCEPROP 3 LASTPIN (-2825 2625) SIG_NAME P3E_CPU1_PE3_MP_TXN<8>
J 0
(-2815 2635);
DISPLAY 0.659574 (-2815 2635);
PAINT MONO (-2815 2635);
DISPLAY INVISIBLE (-2815 2635);
FORCEPROP 1 LASTPIN (-2825 2625) BN 8
J 0
(-2837 2633);
DISPLAY 0.617021 (-2837 2633);
PAINT GREEN (-2837 2633);
FORCEPROP 2 LAST CDS_LIB mstr_standard
J 2
(-2775 2625);
PAINT MONO (-2775 2625);
DISPLAY INVISIBLE (-2775 2625);
FORCEPROP 1 LAST BODY_TYPE PLUMBING
J 0
(-2775 2675);
DISPLAY 1.446809 (-2775 2675);
PAINT GREEN (-2775 2675);
DISPLAY INVISIBLE (-2775 2675);
FORCEPROP 1 LAST HDL_TAP TRUE
J 0
(-2450 2500);
DISPLAY 1.446809 (-2450 2500);
PAINT GREEN (-2450 2500);
DISPLAY INVISIBLE (-2450 2500);
FORCEPROP 1 LAST PATH I58
J 0
(-2777 2625);
DISPLAY 0.872340 (-2777 2625);
PAINT GREEN (-2777 2625);
DISPLAY INVISIBLE (-2777 2625);
FORCEADD TAP..1
(-2775 2725);
FORCEPROP 3 LASTPIN (-2825 2725) SIG_NAME P3E_CPU1_PE3_MP_TXN<10>
J 0
(-2815 2735);
DISPLAY 0.659574 (-2815 2735);
PAINT MONO (-2815 2735);
DISPLAY INVISIBLE (-2815 2735);
FORCEPROP 1 LASTPIN (-2825 2725) BN 10
J 0
(-2837 2733);
DISPLAY 0.617021 (-2837 2733);
PAINT GREEN (-2837 2733);
FORCEPROP 2 LAST CDS_LIB mstr_standard
J 2
(-2775 2725);
PAINT MONO (-2775 2725);
DISPLAY INVISIBLE (-2775 2725);
FORCEPROP 1 LAST BODY_TYPE PLUMBING
J 0
(-2775 2775);
DISPLAY 1.446809 (-2775 2775);
PAINT GREEN (-2775 2775);
DISPLAY INVISIBLE (-2775 2775);
FORCEPROP 1 LAST HDL_TAP TRUE
J 0
(-2450 2600);
DISPLAY 1.446809 (-2450 2600);
PAINT GREEN (-2450 2600);
DISPLAY INVISIBLE (-2450 2600);
FORCEPROP 1 LAST PATH I59
J 0
(-2777 2725);
DISPLAY 0.872340 (-2777 2725);
PAINT GREEN (-2777 2725);
DISPLAY INVISIBLE (-2777 2725);
FORCEADD TAP..1
(-2775 2675);
FORCEPROP 3 LASTPIN (-2825 2675) SIG_NAME P3E_CPU1_PE3_MP_TXN<9>
J 0
(-2815 2685);
DISPLAY 0.659574 (-2815 2685);
PAINT MONO (-2815 2685);
DISPLAY INVISIBLE (-2815 2685);
FORCEPROP 1 LASTPIN (-2825 2675) BN 9
J 0
(-2837 2683);
DISPLAY 0.617021 (-2837 2683);
PAINT GREEN (-2837 2683);
FORCEPROP 2 LAST CDS_LIB mstr_standard
J 2
(-2775 2675);
PAINT MONO (-2775 2675);
DISPLAY INVISIBLE (-2775 2675);
FORCEPROP 1 LAST BODY_TYPE PLUMBING
J 0
(-2775 2725);
DISPLAY 1.446809 (-2775 2725);
PAINT GREEN (-2775 2725);
DISPLAY INVISIBLE (-2775 2725);
FORCEPROP 1 LAST HDL_TAP TRUE
J 0
(-2450 2550);
DISPLAY 1.446809 (-2450 2550);
PAINT GREEN (-2450 2550);
DISPLAY INVISIBLE (-2450 2550);
FORCEPROP 1 LAST PATH I60
J 0
(-2777 2675);
DISPLAY 0.872340 (-2777 2675);
PAINT GREEN (-2777 2675);
DISPLAY INVISIBLE (-2777 2675);
FORCEADD TAP..1
(-2775 2775);
FORCEPROP 3 LASTPIN (-2825 2775) SIG_NAME P3E_CPU1_PE3_MP_TXN<11>
J 0
(-2815 2785);
DISPLAY 0.659574 (-2815 2785);
PAINT MONO (-2815 2785);
DISPLAY INVISIBLE (-2815 2785);
FORCEPROP 1 LASTPIN (-2825 2775) BN 11
J 0
(-2837 2783);
DISPLAY 0.617021 (-2837 2783);
PAINT GREEN (-2837 2783);
FORCEPROP 2 LAST CDS_LIB mstr_standard
J 2
(-2775 2775);
PAINT MONO (-2775 2775);
DISPLAY INVISIBLE (-2775 2775);
FORCEPROP 1 LAST BODY_TYPE PLUMBING
J 0
(-2775 2825);
DISPLAY 1.446809 (-2775 2825);
PAINT GREEN (-2775 2825);
DISPLAY INVISIBLE (-2775 2825);
FORCEPROP 1 LAST HDL_TAP TRUE
J 0
(-2450 2650);
DISPLAY 1.446809 (-2450 2650);
PAINT GREEN (-2450 2650);
DISPLAY INVISIBLE (-2450 2650);
FORCEPROP 1 LAST PATH I61
J 0
(-2777 2775);
DISPLAY 0.872340 (-2777 2775);
PAINT GREEN (-2777 2775);
DISPLAY INVISIBLE (-2777 2775);
FORCEADD TAP..1
(-2925 2925);
FORCEPROP 3 LASTPIN (-2975 2925) SIG_NAME P3E_CPU1_PE3_MP_TXP<9>
J 0
(-2965 2935);
DISPLAY 0.659574 (-2965 2935);
PAINT MONO (-2965 2935);
DISPLAY INVISIBLE (-2965 2935);
FORCEPROP 1 LASTPIN (-2975 2925) BN 9
J 0
(-2987 2933);
DISPLAY 0.617021 (-2987 2933);
PAINT GREEN (-2987 2933);
FORCEPROP 2 LAST CDS_LIB mstr_standard
J 2
(-2925 2925);
PAINT MONO (-2925 2925);
DISPLAY INVISIBLE (-2925 2925);
FORCEPROP 1 LAST BODY_TYPE PLUMBING
J 0
(-2925 2975);
DISPLAY 1.446809 (-2925 2975);
PAINT GREEN (-2925 2975);
DISPLAY INVISIBLE (-2925 2975);
FORCEPROP 1 LAST HDL_TAP TRUE
J 0
(-2600 2800);
DISPLAY 1.446809 (-2600 2800);
PAINT GREEN (-2600 2800);
DISPLAY INVISIBLE (-2600 2800);
FORCEPROP 1 LAST PATH I62
J 0
(-2927 2925);
DISPLAY 0.872340 (-2927 2925);
PAINT GREEN (-2927 2925);
DISPLAY INVISIBLE (-2927 2925);
FORCEADD TAP..1
(-2925 2875);
FORCEPROP 3 LASTPIN (-2975 2875) SIG_NAME P3E_CPU1_PE3_MP_TXP<8>
J 0
(-2965 2885);
DISPLAY 0.659574 (-2965 2885);
PAINT MONO (-2965 2885);
DISPLAY INVISIBLE (-2965 2885);
FORCEPROP 1 LASTPIN (-2975 2875) BN 8
J 0
(-2987 2883);
DISPLAY 0.617021 (-2987 2883);
PAINT GREEN (-2987 2883);
FORCEPROP 2 LAST CDS_LIB mstr_standard
J 2
(-2925 2875);
PAINT MONO (-2925 2875);
DISPLAY INVISIBLE (-2925 2875);
FORCEPROP 1 LAST BODY_TYPE PLUMBING
J 0
(-2925 2925);
DISPLAY 1.446809 (-2925 2925);
PAINT GREEN (-2925 2925);
DISPLAY INVISIBLE (-2925 2925);
FORCEPROP 1 LAST HDL_TAP TRUE
J 0
(-2600 2750);
DISPLAY 1.446809 (-2600 2750);
PAINT GREEN (-2600 2750);
DISPLAY INVISIBLE (-2600 2750);
FORCEPROP 1 LAST PATH I63
J 0
(-2927 2875);
DISPLAY 0.872340 (-2927 2875);
PAINT GREEN (-2927 2875);
DISPLAY INVISIBLE (-2927 2875);
FORCEADD TAP..1
(-2925 3025);
FORCEPROP 3 LASTPIN (-2975 3025) SIG_NAME P3E_CPU1_PE3_MP_TXP<11>
J 0
(-2965 3035);
DISPLAY 0.659574 (-2965 3035);
PAINT MONO (-2965 3035);
DISPLAY INVISIBLE (-2965 3035);
FORCEPROP 1 LASTPIN (-2975 3025) BN 11
J 0
(-2987 3033);
DISPLAY 0.617021 (-2987 3033);
PAINT GREEN (-2987 3033);
FORCEPROP 2 LAST CDS_LIB mstr_standard
J 2
(-2925 3025);
PAINT MONO (-2925 3025);
DISPLAY INVISIBLE (-2925 3025);
FORCEPROP 1 LAST BODY_TYPE PLUMBING
J 0
(-2925 3075);
DISPLAY 1.446809 (-2925 3075);
PAINT GREEN (-2925 3075);
DISPLAY INVISIBLE (-2925 3075);
FORCEPROP 1 LAST HDL_TAP TRUE
J 0
(-2600 2900);
DISPLAY 1.446809 (-2600 2900);
PAINT GREEN (-2600 2900);
DISPLAY INVISIBLE (-2600 2900);
FORCEPROP 1 LAST PATH I64
J 0
(-2927 3025);
DISPLAY 0.872340 (-2927 3025);
PAINT GREEN (-2927 3025);
DISPLAY INVISIBLE (-2927 3025);
FORCEADD TAP..1
(-2925 2975);
FORCEPROP 3 LASTPIN (-2975 2975) SIG_NAME P3E_CPU1_PE3_MP_TXP<10>
J 0
(-2965 2985);
DISPLAY 0.659574 (-2965 2985);
PAINT MONO (-2965 2985);
DISPLAY INVISIBLE (-2965 2985);
FORCEPROP 1 LASTPIN (-2975 2975) BN 10
J 0
(-2987 2983);
DISPLAY 0.617021 (-2987 2983);
PAINT GREEN (-2987 2983);
FORCEPROP 2 LAST CDS_LIB mstr_standard
J 2
(-2925 2975);
PAINT MONO (-2925 2975);
DISPLAY INVISIBLE (-2925 2975);
FORCEPROP 1 LAST BODY_TYPE PLUMBING
J 0
(-2925 3025);
DISPLAY 1.446809 (-2925 3025);
PAINT GREEN (-2925 3025);
DISPLAY INVISIBLE (-2925 3025);
FORCEPROP 1 LAST HDL_TAP TRUE
J 0
(-2600 2850);
DISPLAY 1.446809 (-2600 2850);
PAINT GREEN (-2600 2850);
DISPLAY INVISIBLE (-2600 2850);
FORCEPROP 1 LAST PATH I65
J 0
(-2927 2975);
DISPLAY 0.872340 (-2927 2975);
PAINT GREEN (-2927 2975);
DISPLAY INVISIBLE (-2927 2975);
FORCEADD TAP..1
(-2775 3125);
FORCEPROP 3 LASTPIN (-2825 3125) SIG_NAME P3E_CPU1_PE3_MP_TXN<12>
J 0
(-2815 3135);
DISPLAY 0.659574 (-2815 3135);
PAINT MONO (-2815 3135);
DISPLAY INVISIBLE (-2815 3135);
FORCEPROP 1 LASTPIN (-2825 3125) BN 12
J 0
(-2837 3133);
DISPLAY 0.617021 (-2837 3133);
PAINT GREEN (-2837 3133);
FORCEPROP 2 LAST CDS_LIB mstr_standard
J 2
(-2775 3125);
PAINT MONO (-2775 3125);
DISPLAY INVISIBLE (-2775 3125);
FORCEPROP 1 LAST BODY_TYPE PLUMBING
J 0
(-2775 3175);
DISPLAY 1.446809 (-2775 3175);
PAINT GREEN (-2775 3175);
DISPLAY INVISIBLE (-2775 3175);
FORCEPROP 1 LAST HDL_TAP TRUE
J 0
(-2450 3000);
DISPLAY 1.446809 (-2450 3000);
PAINT GREEN (-2450 3000);
DISPLAY INVISIBLE (-2450 3000);
FORCEPROP 1 LAST PATH I66
J 0
(-2777 3125);
DISPLAY 0.872340 (-2777 3125);
PAINT GREEN (-2777 3125);
DISPLAY INVISIBLE (-2777 3125);
FORCEADD TAP..1
(-2775 3175);
FORCEPROP 3 LASTPIN (-2825 3175) SIG_NAME P3E_CPU1_PE3_MP_TXN<13>
J 0
(-2815 3185);
DISPLAY 0.659574 (-2815 3185);
PAINT MONO (-2815 3185);
DISPLAY INVISIBLE (-2815 3185);
FORCEPROP 1 LASTPIN (-2825 3175) BN 13
J 0
(-2837 3183);
DISPLAY 0.617021 (-2837 3183);
PAINT GREEN (-2837 3183);
FORCEPROP 2 LAST CDS_LIB mstr_standard
J 2
(-2775 3175);
PAINT MONO (-2775 3175);
DISPLAY INVISIBLE (-2775 3175);
FORCEPROP 1 LAST BODY_TYPE PLUMBING
J 0
(-2775 3225);
DISPLAY 1.446809 (-2775 3225);
PAINT GREEN (-2775 3225);
DISPLAY INVISIBLE (-2775 3225);
FORCEPROP 1 LAST HDL_TAP TRUE
J 0
(-2450 3050);
DISPLAY 1.446809 (-2450 3050);
PAINT GREEN (-2450 3050);
DISPLAY INVISIBLE (-2450 3050);
FORCEPROP 1 LAST PATH I67
J 0
(-2777 3175);
DISPLAY 0.872340 (-2777 3175);
PAINT GREEN (-2777 3175);
DISPLAY INVISIBLE (-2777 3175);
FORCEADD TAP..1
(-2775 3225);
FORCEPROP 3 LASTPIN (-2825 3225) SIG_NAME P3E_CPU1_PE3_MP_TXN<14>
J 0
(-2815 3235);
DISPLAY 0.659574 (-2815 3235);
PAINT MONO (-2815 3235);
DISPLAY INVISIBLE (-2815 3235);
FORCEPROP 1 LASTPIN (-2825 3225) BN 14
J 0
(-2837 3233);
DISPLAY 0.617021 (-2837 3233);
PAINT GREEN (-2837 3233);
FORCEPROP 2 LAST CDS_LIB mstr_standard
J 2
(-2775 3225);
PAINT MONO (-2775 3225);
DISPLAY INVISIBLE (-2775 3225);
FORCEPROP 1 LAST BODY_TYPE PLUMBING
J 0
(-2775 3275);
DISPLAY 1.446809 (-2775 3275);
PAINT GREEN (-2775 3275);
DISPLAY INVISIBLE (-2775 3275);
FORCEPROP 1 LAST HDL_TAP TRUE
J 0
(-2450 3100);
DISPLAY 1.446809 (-2450 3100);
PAINT GREEN (-2450 3100);
DISPLAY INVISIBLE (-2450 3100);
FORCEPROP 1 LAST PATH I68
J 0
(-2777 3225);
DISPLAY 0.872340 (-2777 3225);
PAINT GREEN (-2777 3225);
DISPLAY INVISIBLE (-2777 3225);
FORCEADD TAP..1
(-2775 3275);
FORCEPROP 3 LASTPIN (-2825 3275) SIG_NAME P3E_CPU1_PE3_MP_TXN<15>
J 0
(-2815 3285);
DISPLAY 0.659574 (-2815 3285);
PAINT MONO (-2815 3285);
DISPLAY INVISIBLE (-2815 3285);
FORCEPROP 1 LASTPIN (-2825 3275) BN 15
J 0
(-2837 3283);
DISPLAY 0.617021 (-2837 3283);
PAINT GREEN (-2837 3283);
FORCEPROP 2 LAST CDS_LIB mstr_standard
J 2
(-2775 3275);
PAINT MONO (-2775 3275);
DISPLAY INVISIBLE (-2775 3275);
FORCEPROP 1 LAST BODY_TYPE PLUMBING
J 0
(-2775 3325);
DISPLAY 1.446809 (-2775 3325);
PAINT GREEN (-2775 3325);
DISPLAY INVISIBLE (-2775 3325);
FORCEPROP 1 LAST HDL_TAP TRUE
J 0
(-2450 3150);
DISPLAY 1.446809 (-2450 3150);
PAINT GREEN (-2450 3150);
DISPLAY INVISIBLE (-2450 3150);
FORCEPROP 1 LAST PATH I69
J 0
(-2777 3275);
DISPLAY 0.872340 (-2777 3275);
PAINT GREEN (-2777 3275);
DISPLAY INVISIBLE (-2777 3275);
FORCEADD TAP..1
(-2925 3425);
FORCEPROP 3 LASTPIN (-2975 3425) SIG_NAME P3E_CPU1_PE3_MP_TXP<13>
J 0
(-2965 3435);
DISPLAY 0.659574 (-2965 3435);
PAINT MONO (-2965 3435);
DISPLAY INVISIBLE (-2965 3435);
FORCEPROP 1 LASTPIN (-2975 3425) BN 13
J 0
(-2987 3433);
DISPLAY 0.617021 (-2987 3433);
PAINT GREEN (-2987 3433);
FORCEPROP 2 LAST CDS_LIB mstr_standard
J 2
(-2925 3425);
PAINT MONO (-2925 3425);
DISPLAY INVISIBLE (-2925 3425);
FORCEPROP 1 LAST BODY_TYPE PLUMBING
J 0
(-2925 3475);
DISPLAY 1.446809 (-2925 3475);
PAINT GREEN (-2925 3475);
DISPLAY INVISIBLE (-2925 3475);
FORCEPROP 1 LAST HDL_TAP TRUE
J 0
(-2600 3300);
DISPLAY 1.446809 (-2600 3300);
PAINT GREEN (-2600 3300);
DISPLAY INVISIBLE (-2600 3300);
FORCEPROP 1 LAST PATH I70
J 0
(-2927 3425);
DISPLAY 0.872340 (-2927 3425);
PAINT GREEN (-2927 3425);
DISPLAY INVISIBLE (-2927 3425);
FORCEADD TAP..1
(-2925 3375);
FORCEPROP 3 LASTPIN (-2975 3375) SIG_NAME P3E_CPU1_PE3_MP_TXP<12>
J 0
(-2965 3385);
DISPLAY 0.659574 (-2965 3385);
PAINT MONO (-2965 3385);
DISPLAY INVISIBLE (-2965 3385);
FORCEPROP 1 LASTPIN (-2975 3375) BN 12
J 0
(-2987 3383);
DISPLAY 0.617021 (-2987 3383);
PAINT GREEN (-2987 3383);
FORCEPROP 2 LAST CDS_LIB mstr_standard
J 2
(-2925 3375);
PAINT MONO (-2925 3375);
DISPLAY INVISIBLE (-2925 3375);
FORCEPROP 1 LAST BODY_TYPE PLUMBING
J 0
(-2925 3425);
DISPLAY 1.446809 (-2925 3425);
PAINT GREEN (-2925 3425);
DISPLAY INVISIBLE (-2925 3425);
FORCEPROP 1 LAST HDL_TAP TRUE
J 0
(-2600 3250);
DISPLAY 1.446809 (-2600 3250);
PAINT GREEN (-2600 3250);
DISPLAY INVISIBLE (-2600 3250);
FORCEPROP 1 LAST PATH I71
J 0
(-2927 3375);
DISPLAY 0.872340 (-2927 3375);
PAINT GREEN (-2927 3375);
DISPLAY INVISIBLE (-2927 3375);
FORCEADD TAP..1
(-2925 3475);
FORCEPROP 3 LASTPIN (-2975 3475) SIG_NAME P3E_CPU1_PE3_MP_TXP<14>
J 0
(-2965 3485);
DISPLAY 0.659574 (-2965 3485);
PAINT MONO (-2965 3485);
DISPLAY INVISIBLE (-2965 3485);
FORCEPROP 1 LASTPIN (-2975 3475) BN 14
J 0
(-2987 3483);
DISPLAY 0.617021 (-2987 3483);
PAINT GREEN (-2987 3483);
FORCEPROP 2 LAST CDS_LIB mstr_standard
J 2
(-2925 3475);
PAINT MONO (-2925 3475);
DISPLAY INVISIBLE (-2925 3475);
FORCEPROP 1 LAST BODY_TYPE PLUMBING
J 0
(-2925 3525);
DISPLAY 1.446809 (-2925 3525);
PAINT GREEN (-2925 3525);
DISPLAY INVISIBLE (-2925 3525);
FORCEPROP 1 LAST HDL_TAP TRUE
J 0
(-2600 3350);
DISPLAY 1.446809 (-2600 3350);
PAINT GREEN (-2600 3350);
DISPLAY INVISIBLE (-2600 3350);
FORCEPROP 1 LAST PATH I72
J 0
(-2927 3475);
DISPLAY 0.872340 (-2927 3475);
PAINT GREEN (-2927 3475);
DISPLAY INVISIBLE (-2927 3475);
FORCEADD TAP..1
(-2925 3525);
FORCEPROP 3 LASTPIN (-2975 3525) SIG_NAME P3E_CPU1_PE3_MP_TXP<15>
J 0
(-2965 3535);
DISPLAY 0.659574 (-2965 3535);
PAINT MONO (-2965 3535);
DISPLAY INVISIBLE (-2965 3535);
FORCEPROP 1 LASTPIN (-2975 3525) BN 15
J 0
(-2987 3533);
DISPLAY 0.617021 (-2987 3533);
PAINT GREEN (-2987 3533);
FORCEPROP 2 LAST CDS_LIB mstr_standard
J 2
(-2925 3525);
PAINT MONO (-2925 3525);
DISPLAY INVISIBLE (-2925 3525);
FORCEPROP 1 LAST BODY_TYPE PLUMBING
J 0
(-2925 3575);
DISPLAY 1.446809 (-2925 3575);
PAINT GREEN (-2925 3575);
DISPLAY INVISIBLE (-2925 3575);
FORCEPROP 1 LAST HDL_TAP TRUE
J 0
(-2600 3400);
DISPLAY 1.446809 (-2600 3400);
PAINT GREEN (-2600 3400);
DISPLAY INVISIBLE (-2600 3400);
FORCEPROP 1 LAST PATH I73
J 0
(-2927 3525);
DISPLAY 0.872340 (-2927 3525);
PAINT GREEN (-2927 3525);
DISPLAY INVISIBLE (-2927 3525);
FORCEADD OFFPAGE..1
(-6900 1525);
FORCEPROP 2 LAST $XR0 181 
J 0
(-7152 1525);
DISPLAY 0.638298 (-7152 1525);
PAINT MONO (-7152 1525);
FORCEPROP 2 LAST CDS_LIB mstr_standard
J 0
(-6900 1525);
PAINT ORANGE (-6900 1525);
DISPLAY INVISIBLE (-6900 1525);
FORCEPROP 1 LAST OFFPAGE TRUE
J 0
(-6575 1400);
DISPLAY 0.872340 (-6575 1400);
PAINT GREEN (-6575 1400);
DISPLAY INVISIBLE (-6575 1400);
FORCEPROP 1 LAST COMMENT_BODY TRUE
J 0
(-6775 1425);
DISPLAY 0.872340 (-6775 1425);
PAINT GREEN (-6775 1425);
DISPLAY INVISIBLE (-6775 1425);
FORCEPROP 2 LAST PATH I75
J 0
(-6850 1600);
DISPLAY 1.021277 (-6850 1600);
PAINT ORANGE (-6850 1600);
DISPLAY INVISIBLE (-6850 1600);
FORCEADD OFFPAGE..1
(-6900 1400);
FORCEPROP 2 LAST $XR0 181 
J 0
(-7152 1400);
DISPLAY 0.638298 (-7152 1400);
PAINT MONO (-7152 1400);
FORCEPROP 2 LAST CDS_LIB mstr_standard
J 0
(-6900 1400);
PAINT ORANGE (-6900 1400);
DISPLAY INVISIBLE (-6900 1400);
FORCEPROP 1 LAST OFFPAGE TRUE
J 0
(-6575 1275);
DISPLAY 0.872340 (-6575 1275);
PAINT GREEN (-6575 1275);
DISPLAY INVISIBLE (-6575 1275);
FORCEPROP 1 LAST COMMENT_BODY TRUE
J 0
(-6775 1300);
DISPLAY 0.872340 (-6775 1300);
PAINT GREEN (-6775 1300);
DISPLAY INVISIBLE (-6775 1300);
FORCEPROP 2 LAST PATH I76
J 0
(-6850 1475);
DISPLAY 1.021277 (-6850 1475);
PAINT ORANGE (-6850 1475);
DISPLAY INVISIBLE (-6850 1475);
FORCEADD OFFPAGE..2
(-1700 1475);
FORCEPROP 2 LAST $XR0 181 
J 0
(-1511 1475);
DISPLAY 0.638298 (-1511 1475);
PAINT MONO (-1511 1475);
FORCEPROP 2 LAST CDS_LIB mstr_standard
J 0
(-1700 1475);
PAINT ORANGE (-1700 1475);
DISPLAY INVISIBLE (-1700 1475);
FORCEPROP 1 LAST OFFPAGE TRUE
J 0
(-1375 1350);
DISPLAY 0.872340 (-1375 1350);
PAINT GREEN (-1375 1350);
DISPLAY INVISIBLE (-1375 1350);
FORCEPROP 1 LAST COMMENT_BODY TRUE
J 0
(-1745 1380);
DISPLAY 0.872340 (-1745 1380);
PAINT GREEN (-1745 1380);
DISPLAY INVISIBLE (-1745 1380);
FORCEPROP 2 LAST PATH I77
J 0
(-1650 1550);
DISPLAY 1.021277 (-1650 1550);
PAINT ORANGE (-1650 1550);
DISPLAY INVISIBLE (-1650 1550);
FORCEADD OFFPAGE..2
(-1700 1375);
FORCEPROP 2 LAST $XR0 181 
J 0
(-1511 1375);
DISPLAY 0.638298 (-1511 1375);
PAINT MONO (-1511 1375);
FORCEPROP 2 LAST CDS_LIB mstr_standard
J 0
(-1700 1375);
PAINT ORANGE (-1700 1375);
DISPLAY INVISIBLE (-1700 1375);
FORCEPROP 1 LAST OFFPAGE TRUE
J 0
(-1375 1250);
DISPLAY 0.872340 (-1375 1250);
PAINT GREEN (-1375 1250);
DISPLAY INVISIBLE (-1375 1250);
FORCEPROP 1 LAST COMMENT_BODY TRUE
J 0
(-1745 1280);
DISPLAY 0.872340 (-1745 1280);
PAINT GREEN (-1745 1280);
DISPLAY INVISIBLE (-1745 1280);
FORCEPROP 2 LAST PATH I78
J 0
(-1525 1450);
DISPLAY 1.021277 (-1525 1450);
PAINT ORANGE (-1525 1450);
DISPLAY INVISIBLE (-1525 1450);
FORCEADD OFFPAGE..2
(-1500 3625);
FORCEPROP 2 LAST $XR0 182 
J 0
(-1311 3625);
DISPLAY 0.638298 (-1311 3625);
PAINT MONO (-1311 3625);
FORCEPROP 2 LAST CDS_LIB mstr_standard
J 0
(-1500 3625);
PAINT ORANGE (-1500 3625);
DISPLAY INVISIBLE (-1500 3625);
FORCEPROP 1 LAST OFFPAGE TRUE
J 0
(-1175 3500);
DISPLAY 0.872340 (-1175 3500);
PAINT GREEN (-1175 3500);
DISPLAY INVISIBLE (-1175 3500);
FORCEPROP 1 LAST COMMENT_BODY TRUE
J 0
(-1545 3530);
DISPLAY 0.872340 (-1545 3530);
PAINT GREEN (-1545 3530);
DISPLAY INVISIBLE (-1545 3530);
FORCEPROP 2 LAST PATH I80
J 0
(-1325 3700);
DISPLAY 1.021277 (-1325 3700);
PAINT ORANGE (-1325 3700);
DISPLAY INVISIBLE (-1325 3700);
FORCEADD OFFPAGE..2
(-1500 3500);
FORCEPROP 2 LAST $XR0 182 
J 0
(-1311 3500);
DISPLAY 0.638298 (-1311 3500);
PAINT MONO (-1311 3500);
FORCEPROP 2 LAST CDS_LIB mstr_standard
J 0
(-1500 3500);
PAINT ORANGE (-1500 3500);
DISPLAY INVISIBLE (-1500 3500);
FORCEPROP 1 LAST OFFPAGE TRUE
J 0
(-1175 3375);
DISPLAY 0.872340 (-1175 3375);
PAINT GREEN (-1175 3375);
DISPLAY INVISIBLE (-1175 3375);
FORCEPROP 1 LAST COMMENT_BODY TRUE
J 0
(-1545 3405);
DISPLAY 0.872340 (-1545 3405);
PAINT GREEN (-1545 3405);
DISPLAY INVISIBLE (-1545 3405);
FORCEPROP 2 LAST PATH I81
J 0
(-1325 3575);
DISPLAY 1.021277 (-1325 3575);
PAINT ORANGE (-1325 3575);
DISPLAY INVISIBLE (-1325 3575);
FORCEADD OFFPAGE..1
(-6800 3700);
FORCEPROP 2 LAST $XR0 182 
J 0
(-7052 3700);
DISPLAY 0.638298 (-7052 3700);
PAINT MONO (-7052 3700);
FORCEPROP 2 LAST CDS_LIB mstr_standard
J 0
(-6800 3700);
PAINT ORANGE (-6800 3700);
DISPLAY INVISIBLE (-6800 3700);
FORCEPROP 1 LAST OFFPAGE TRUE
J 0
(-6475 3575);
DISPLAY 0.872340 (-6475 3575);
PAINT GREEN (-6475 3575);
DISPLAY INVISIBLE (-6475 3575);
FORCEPROP 1 LAST COMMENT_BODY TRUE
J 0
(-6675 3600);
DISPLAY 0.872340 (-6675 3600);
PAINT GREEN (-6675 3600);
DISPLAY INVISIBLE (-6675 3600);
FORCEPROP 2 LAST PATH I82
J 0
(-6750 3775);
DISPLAY 1.021277 (-6750 3775);
PAINT ORANGE (-6750 3775);
DISPLAY INVISIBLE (-6750 3775);
FORCEADD OFFPAGE..1
(-6800 3600);
FORCEPROP 2 LAST $XR0 182 
J 0
(-7052 3600);
DISPLAY 0.638298 (-7052 3600);
PAINT MONO (-7052 3600);
FORCEPROP 2 LAST CDS_LIB mstr_standard
J 0
(-6800 3600);
PAINT ORANGE (-6800 3600);
DISPLAY INVISIBLE (-6800 3600);
FORCEPROP 1 LAST OFFPAGE TRUE
J 0
(-6475 3475);
DISPLAY 0.872340 (-6475 3475);
PAINT GREEN (-6475 3475);
DISPLAY INVISIBLE (-6475 3475);
FORCEPROP 1 LAST COMMENT_BODY TRUE
J 0
(-6675 3500);
DISPLAY 0.872340 (-6675 3500);
PAINT GREEN (-6675 3500);
DISPLAY INVISIBLE (-6675 3500);
FORCEPROP 2 LAST PATH I83
J 0
(-6750 3675);
DISPLAY 1.021277 (-6750 3675);
PAINT ORANGE (-6750 3675);
DISPLAY INVISIBLE (-6750 3675);
FORCEADD SKX_EXT_B..12
(-4125 2575);
FORCEPROP 1 LAST LOCATION U2D1
J 0
(-4825 3775);
DISPLAY 0.617021 (-4825 3775);
PAINT AQUA (-4825 3775);
FORCEPROP 1 LAST PART_NUMBER TBD
J 0
(-4825 1425);
DISPLAY 0.617021 (-4825 1425);
PAINT BLUE (-4825 1425);
FORCEPROP 1 LAST MATERIAL IC
J 0
(-4825 3725);
DISPLAY 0.617021 (-4825 3725);
PAINT SKYBLUE (-4825 3725);
FORCEPROP 2 LASTPIN (-3375 3525) $PN CV5
J 0
(-3365 3535);
DISPLAY 0.617021 (-3365 3535);
PAINT ORANGE (-3365 3535);
FORCEPROP 2 LASTPIN (-3375 3475) $PN DA4
J 0
(-3365 3485);
DISPLAY 0.617021 (-3365 3485);
PAINT ORANGE (-3365 3485);
FORCEPROP 2 LASTPIN (-3375 3425) $PN DC6
J 0
(-3365 3435);
DISPLAY 0.617021 (-3365 3435);
PAINT ORANGE (-3365 3435);
FORCEPROP 2 LASTPIN (-3375 3375) $PN DG6
J 0
(-3365 3385);
DISPLAY 0.617021 (-3365 3385);
PAINT ORANGE (-3365 3385);
FORCEPROP 2 LASTPIN (-3375 3025) $PN DH5
J 0
(-3365 3035);
DISPLAY 0.617021 (-3365 3035);
PAINT ORANGE (-3365 3035);
FORCEPROP 2 LASTPIN (-3375 2975) $PN DK5
J 0
(-3365 2985);
DISPLAY 0.617021 (-3365 2985);
PAINT ORANGE (-3365 2985);
FORCEPROP 2 LASTPIN (-3375 2925) $PN DM5
J 0
(-3365 2935);
DISPLAY 0.617021 (-3365 2935);
PAINT ORANGE (-3365 2935);
FORCEPROP 2 LASTPIN (-3375 2875) $PN DN6
J 0
(-3365 2885);
DISPLAY 0.617021 (-3365 2885);
PAINT ORANGE (-3365 2885);
FORCEPROP 2 LASTPIN (-3375 2525) $PN DP7
J 0
(-3365 2535);
DISPLAY 0.617021 (-3365 2535);
PAINT ORANGE (-3365 2535);
FORCEPROP 2 LASTPIN (-3375 2475) $PN DT9
J 0
(-3365 2485);
DISPLAY 0.617021 (-3365 2485);
PAINT ORANGE (-3365 2485);
FORCEPROP 2 LASTPIN (-3375 2425) $PN DV9
J 0
(-3365 2435);
DISPLAY 0.617021 (-3365 2435);
PAINT ORANGE (-3365 2435);
FORCEPROP 2 LASTPIN (-3375 2375) $PN DY9
J 0
(-3365 2385);
DISPLAY 0.617021 (-3365 2385);
PAINT ORANGE (-3365 2385);
FORCEPROP 2 LASTPIN (-3375 2025) $PN EA10
J 0
(-3365 2035);
DISPLAY 0.617021 (-3365 2035);
PAINT ORANGE (-3365 2035);
FORCEPROP 2 LASTPIN (-3375 1975) $PN EB11
J 0
(-3365 1985);
DISPLAY 0.617021 (-3365 1985);
PAINT ORANGE (-3365 1985);
FORCEPROP 2 LASTPIN (-3375 1925) $PN ED13
J 0
(-3365 1935);
DISPLAY 0.617021 (-3365 1935);
PAINT ORANGE (-3365 1935);
FORCEPROP 2 LASTPIN (-3375 1875) $PN EC14
J 0
(-3365 1885);
DISPLAY 0.617021 (-3365 1885);
PAINT ORANGE (-3365 1885);
FORCEPROP 2 LASTPIN (-3375 3275) $PN CY5
J 0
(-3365 3285);
DISPLAY 0.617021 (-3365 3285);
PAINT ORANGE (-3365 3285);
FORCEPROP 2 LASTPIN (-3375 3225) $PN DB5
J 0
(-3365 3235);
DISPLAY 0.617021 (-3365 3235);
PAINT ORANGE (-3365 3235);
FORCEPROP 2 LASTPIN (-3375 3175) $PN DD5
J 0
(-3365 3185);
DISPLAY 0.617021 (-3365 3185);
PAINT ORANGE (-3365 3185);
FORCEPROP 2 LASTPIN (-3375 3125) $PN DJ6
J 0
(-3365 3135);
DISPLAY 0.617021 (-3365 3135);
PAINT ORANGE (-3365 3135);
FORCEPROP 2 LASTPIN (-3375 2775) $PN DJ4
J 0
(-3365 2785);
DISPLAY 0.617021 (-3365 2785);
PAINT ORANGE (-3365 2785);
FORCEPROP 2 LASTPIN (-3375 2725) $PN DL6
J 0
(-3365 2735);
DISPLAY 0.617021 (-3365 2735);
PAINT ORANGE (-3365 2735);
FORCEPROP 2 LASTPIN (-3375 2675) $PN DP5
J 0
(-3365 2685);
DISPLAY 0.617021 (-3365 2685);
PAINT ORANGE (-3365 2685);
FORCEPROP 2 LASTPIN (-3375 2625) $PN DM7
J 0
(-3365 2635);
DISPLAY 0.617021 (-3365 2635);
PAINT ORANGE (-3365 2635);
FORCEPROP 2 LASTPIN (-3375 2275) $PN DR8
J 0
(-3365 2285);
DISPLAY 0.617021 (-3365 2285);
PAINT ORANGE (-3365 2285);
FORCEPROP 2 LASTPIN (-3375 2225) $PN DU8
J 0
(-3365 2235);
DISPLAY 0.617021 (-3365 2235);
PAINT ORANGE (-3365 2235);
FORCEPROP 2 LASTPIN (-3375 2175) $PN DW10
J 0
(-3365 2185);
DISPLAY 0.617021 (-3365 2185);
PAINT ORANGE (-3365 2185);
FORCEPROP 2 LASTPIN (-3375 2125) $PN EB9
J 0
(-3365 2135);
DISPLAY 0.617021 (-3365 2135);
PAINT ORANGE (-3365 2135);
FORCEPROP 2 LASTPIN (-3375 1775) $PN DY11
J 0
(-3365 1785);
DISPLAY 0.617021 (-3365 1785);
PAINT ORANGE (-3365 1785);
FORCEPROP 2 LASTPIN (-3375 1725) $PN EC12
J 0
(-3365 1735);
DISPLAY 0.617021 (-3365 1735);
PAINT ORANGE (-3365 1735);
FORCEPROP 2 LASTPIN (-3375 1675) $PN EE12
J 0
(-3365 1685);
DISPLAY 0.617021 (-3365 1685);
PAINT ORANGE (-3365 1685);
FORCEPROP 2 LASTPIN (-3375 1625) $PN EE14
J 0
(-3365 1635);
DISPLAY 0.617021 (-3365 1635);
PAINT ORANGE (-3365 1635);
FORCEPROP 2 LASTPIN (-4875 3525) $PN CU10
J 2
(-4885 3535);
DISPLAY 0.617021 (-4885 3535);
PAINT ORANGE (-4885 3535);
FORCEPROP 2 LASTPIN (-4875 3475) $PN CW10
J 2
(-4885 3485);
DISPLAY 0.617021 (-4885 3485);
PAINT ORANGE (-4885 3485);
FORCEPROP 2 LASTPIN (-4875 3425) $PN DA12
J 2
(-4885 3435);
DISPLAY 0.617021 (-4885 3435);
PAINT ORANGE (-4885 3435);
FORCEPROP 2 LASTPIN (-4875 3375) $PN DC12
J 2
(-4885 3385);
DISPLAY 0.617021 (-4885 3385);
PAINT ORANGE (-4885 3385);
FORCEPROP 2 LASTPIN (-4875 3025) $PN DF11
J 2
(-4885 3035);
DISPLAY 0.617021 (-4885 3035);
PAINT ORANGE (-4885 3035);
FORCEPROP 2 LASTPIN (-4875 2975) $PN DE12
J 2
(-4885 2985);
DISPLAY 0.617021 (-4885 2985);
PAINT ORANGE (-4885 2985);
FORCEPROP 2 LASTPIN (-4875 2925) $PN DH11
J 2
(-4885 2935);
DISPLAY 0.617021 (-4885 2935);
PAINT ORANGE (-4885 2935);
FORCEPROP 2 LASTPIN (-4875 2875) $PN DK13
J 2
(-4885 2885);
DISPLAY 0.617021 (-4885 2885);
PAINT ORANGE (-4885 2885);
FORCEPROP 2 LASTPIN (-4875 2525) $PN DJ14
J 2
(-4885 2535);
DISPLAY 0.617021 (-4885 2535);
PAINT ORANGE (-4885 2535);
FORCEPROP 2 LASTPIN (-4875 2475) $PN DM13
J 2
(-4885 2485);
DISPLAY 0.617021 (-4885 2485);
PAINT ORANGE (-4885 2485);
FORCEPROP 2 LASTPIN (-4875 2425) $PN DP15
J 2
(-4885 2435);
DISPLAY 0.617021 (-4885 2435);
PAINT ORANGE (-4885 2435);
FORCEPROP 2 LASTPIN (-4875 2375) $PN DN16
J 2
(-4885 2385);
DISPLAY 0.617021 (-4885 2385);
PAINT ORANGE (-4885 2385);
FORCEPROP 2 LASTPIN (-4875 2025) $PN DR18
J 2
(-4885 2035);
DISPLAY 0.617021 (-4885 2035);
PAINT ORANGE (-4885 2035);
FORCEPROP 2 LASTPIN (-4875 1975) $PN DV17
J 2
(-4885 1985);
DISPLAY 0.617021 (-4885 1985);
PAINT ORANGE (-4885 1985);
FORCEPROP 2 LASTPIN (-4875 1925) $PN DU18
J 2
(-4885 1935);
DISPLAY 0.617021 (-4885 1935);
PAINT ORANGE (-4885 1935);
FORCEPROP 2 LASTPIN (-4875 1875) $PN DY17
J 2
(-4885 1885);
DISPLAY 0.617021 (-4885 1885);
PAINT ORANGE (-4885 1885);
FORCEPROP 2 LASTPIN (-4875 3275) $PN CV9
J 2
(-4885 3285);
DISPLAY 0.617021 (-4885 3285);
PAINT ORANGE (-4885 3285);
FORCEPROP 2 LASTPIN (-4875 3225) $PN CY11
J 2
(-4885 3235);
DISPLAY 0.617021 (-4885 3235);
PAINT ORANGE (-4885 3235);
FORCEPROP 2 LASTPIN (-4875 3175) $PN DB11
J 2
(-4885 3185);
DISPLAY 0.617021 (-4885 3185);
PAINT ORANGE (-4885 3185);
FORCEPROP 2 LASTPIN (-4875 3125) $PN DD13
J 2
(-4885 3135);
DISPLAY 0.617021 (-4885 3135);
PAINT ORANGE (-4885 3135);
FORCEPROP 2 LASTPIN (-4875 2775) $PN DG10
J 2
(-4885 2785);
DISPLAY 0.617021 (-4885 2785);
PAINT ORANGE (-4885 2785);
FORCEPROP 2 LASTPIN (-4875 2725) $PN DG12
J 2
(-4885 2735);
DISPLAY 0.617021 (-4885 2735);
PAINT ORANGE (-4885 2735);
FORCEPROP 2 LASTPIN (-4875 2675) $PN DJ12
J 2
(-4885 2685);
DISPLAY 0.617021 (-4885 2685);
PAINT ORANGE (-4885 2685);
FORCEPROP 2 LASTPIN (-4875 2625) $PN DL12
J 2
(-4885 2635);
DISPLAY 0.617021 (-4885 2635);
PAINT ORANGE (-4885 2635);
FORCEPROP 2 LASTPIN (-4875 2275) $PN DL14
J 2
(-4885 2285);
DISPLAY 0.617021 (-4885 2285);
PAINT ORANGE (-4885 2285);
FORCEPROP 2 LASTPIN (-4875 2225) $PN DN14
J 2
(-4885 2235);
DISPLAY 0.617021 (-4885 2235);
PAINT ORANGE (-4885 2235);
FORCEPROP 2 LASTPIN (-4875 2175) $PN DR14
J 2
(-4885 2185);
DISPLAY 0.617021 (-4885 2185);
PAINT ORANGE (-4885 2185);
FORCEPROP 2 LASTPIN (-4875 2125) $PN DR16
J 2
(-4885 2135);
DISPLAY 0.617021 (-4885 2135);
PAINT ORANGE (-4885 2135);
FORCEPROP 2 LASTPIN (-4875 1775) $PN DT19
J 2
(-4885 1785);
DISPLAY 0.617021 (-4885 1785);
PAINT ORANGE (-4885 1785);
FORCEPROP 2 LASTPIN (-4875 1725) $PN DW16
J 2
(-4885 1735);
DISPLAY 0.617021 (-4885 1735);
PAINT ORANGE (-4885 1735);
FORCEPROP 2 LASTPIN (-4875 1675) $PN DW18
J 2
(-4885 1685);
DISPLAY 0.617021 (-4885 1685);
PAINT ORANGE (-4885 1685);
FORCEPROP 2 LASTPIN (-4875 1625) $PN EA18
J 2
(-4885 1635);
DISPLAY 0.617021 (-4885 1635);
PAINT ORANGE (-4885 1635);
FORCEPROP 1 LAST PACK_TYPE BGA1
J 0
(-4825 3825);
PAINT SKYBLUE (-4825 3825);
DISPLAY INVISIBLE (-4825 3825);
FORCEPROP 2 LAST SEC_TYPE BGA1
J 0
(-4825 3825);
DISPLAY 1.021277 (-4825 3825);
PAINT ORANGE (-4825 3825);
DISPLAY INVISIBLE (-4825 3825);
FORCEPROP 2 LAST CDS_LIB chpset_lib
J 0
(-4125 2575);
PAINT ORANGE (-4125 2575);
DISPLAY INVISIBLE (-4125 2575);
FORCEPROP 2 LAST SEC 12
J 0
(-4825 3825);
DISPLAY 0.680851 (-4825 3825);
PAINT MONO (-4825 3825);
DISPLAY INVISIBLE (-4825 3825);
FORCEPROP 2 LAST CDS_LOCATION U2D1
J 0
(-4825 3775);
DISPLAY 0.617021 (-4825 3775);
PAINT AQUA (-4825 3775);
DISPLAY INVISIBLE (-4825 3775);
FORCEPROP 1 LAST PATH I84
J 0
(-4125 3725);
PAINT GREEN (-4125 3725);
DISPLAY INVISIBLE (-4125 3725);
FORCEADD DESIGN_NOTE..1
(-4625 1325);
FORCEPROP 0 LAST L1 CPU SYMBOLS 1-30 ARE PRELIMINARY AND SUBJECT TO CHANGE
J 0
(-4825 1200);
DISPLAY 1.021277 (-4825 1200);
PAINT ORANGE (-4825 1200);
FORCEPROP 2 LAST CDS_LIB mstr_symbols
J 0
(-4625 1325);
PAINT ORANGE (-4625 1325);
DISPLAY INVISIBLE (-4625 1325);
FORCEPROP 1 LAST COMMENT_BODY TRUE
J 0
(-4600 1425);
DISPLAY 0.978723 (-4600 1425);
PAINT ORANGE (-4600 1425);
DISPLAY INVISIBLE (-4600 1425);
FORCEADD INTEL_CORP_BPAGE..1
(0 0);
FORCEPROP 1 LAST CDS_CON_LAST_MODIFIED Fri Jun 16 17:48:25 2017
J 0
(-1425 325);
DISPLAY 1.340426 (-1425 325);
PAINT GREEN (-1425 325);
DISPLAY INVISIBLE (-1425 325);
FORCEPROP 1 LAST CUSTOM_TXT_CDS <CURRENT_DESIGN_SHEET> OF <TOTAL_DESIGN_SHEETS>
J 0
(-500 25);
PAINT ORANGE (-500 25);
FORCEPROP 1 LAST CUSTOM_TXT_CDS <CON_LAST_MODIFIED>
J 0
(-4000 100);
PAINT ORANGE (-4000 100);
FORCEPROP 2 LAST CUSTOM_TXT_CDS <XR_PAGE_TITLE>
J 0
(-7890 5250);
DISPLAY 0.638298 (-7890 5250);
PAINT PINK (-7890 5250);
DISPLAY INVISIBLE (-7890 5250);
FORCEPROP 1 LAST SCH_TITLE SKYLAKE - SKT1 - 12 OF 21
J 0
(-7950 50);
DISPLAY 1.212766 (-7950 50);
PAINT GREEN (-7950 50);
FORCEPROP 2 LAST PAGE_BORDER TRUE
J 0
(-7890 5250);
DISPLAY 0.851064 (-7890 5250);
PAINT PINK (-7890 5250);
DISPLAY INVISIBLE (-7890 5250);
FORCEPROP 2 LAST CDS_LIB mstr_symbols
J 0
(0 0);
PAINT ORANGE (0 0);
DISPLAY INVISIBLE (0 0);
FORCEPROP 1 LAST COMMENT_BODY TRUE
J 0
(12 12);
DISPLAY 0.638298 (12 12);
PAINT GREEN (12 12);
DISPLAY INVISIBLE (12 12);
FORCEPROP 2 LAST CDS_XR_PAGE_TITLE CR-66 : @BASEBOARD_FAB2_LIB.BASEBOARD_FAB2(SCH_1):PAGE66
J 0
(-7890 5250);
DISPLAY 0.638298 (-7890 5250);
PAINT PINK (-7890 5250);
DISPLAY INVISIBLE (-7890 5250);
FORCEADD PRELIM..10
(-4115 2565);
PAINT GRAY (-4115 2565);
FORCEPROP 2 LAST CDS_LIB mstr_misc
J 0
(-4115 2565);
PAINT ORANGE (-4115 2565);
DISPLAY INVISIBLE (-4115 2565);
FORCEPROP 1 LAST COMMENT_BODY TRUE
J 0
(-4115 2565);
PAINT ORANGE (-4115 2565);
DISPLAY INVISIBLE (-4115 2565);
WIRE 17 -1 (-2725 2650)(-2725 2700);
WIRE 17 -1 (-2725 2700)(-2725 2750);
WIRE 17 -1 (-2725 2750)(-2725 2800);
WIRE 17 -1 (-2725 2800)(-2725 3150);
WIRE 17 -1 (-2725 3150)(-2725 3200);
WIRE 17 -1 (-2725 3200)(-2725 3250);
WIRE 17 -1 (-2725 3500)(-1550 3500);
FORCEPROP 2 LAST SIG_NAME P3E_CPU1_PE3_MP_TXN<15:8>
J 0
(-2185 3510);
DISPLAY 0.617021 (-2185 3510);
PAINT ORANGE (-2185 3510);
WIRE 17 -1 (-2725 3250)(-2725 3300);
WIRE 17 -1 (-2725 3300)(-2725 3500);
WIRE 17 -1 (-2725 1475)(-1750 1475);
FORCEPROP 2 LAST SIG_NAME P3E_CPU1_PE3_MP_TXN<7:0>
J 0
(-2460 1485);
DISPLAY 0.617021 (-2460 1485);
PAINT ORANGE (-2460 1485);
WIRE 17 -1 (-2725 1650)(-2725 1475);
WIRE 17 -1 (-2725 1700)(-2725 1650);
WIRE 17 -1 (-2725 1700)(-2725 1750);
WIRE 17 -1 (-2725 1750)(-2725 1800);
WIRE 17 -1 (-2725 1800)(-2725 2150);
WIRE 17 -1 (-2725 2150)(-2725 2200);
WIRE 17 -1 (-2725 2200)(-2725 2250);
WIRE 17 -1 (-2725 2250)(-2725 2300);
WIRE 17 -1 (-2875 2900)(-2875 2950);
WIRE 17 -1 (-2875 2950)(-2875 3000);
WIRE 17 -1 (-2875 3000)(-2875 3050);
WIRE 17 -1 (-2875 3050)(-2875 3400);
WIRE 17 -1 (-2875 3450)(-2875 3400);
WIRE 17 -1 (-2875 3450)(-2875 3500);
WIRE 17 -1 (-2875 3625)(-1550 3625);
FORCEPROP 2 LAST SIG_NAME P3E_CPU1_PE3_MP_TXP<15:8>
J 0
(-2185 3635);
DISPLAY 0.617021 (-2185 3635);
PAINT ORANGE (-2185 3635);
WIRE 17 -1 (-2875 3500)(-2875 3550);
WIRE 17 -1 (-2875 3550)(-2875 3625);
WIRE 17 -1 (-2875 1375)(-1750 1375);
FORCEPROP 2 LAST SIG_NAME P3E_CPU1_PE3_MP_TXP<7:0>
J 0
(-2460 1385);
DISPLAY 0.617021 (-2460 1385);
PAINT ORANGE (-2460 1385);
WIRE 17 -1 (-2875 1900)(-2875 1375);
WIRE 17 -1 (-2875 1900)(-2875 1950);
WIRE 17 -1 (-2875 1950)(-2875 2000);
WIRE 17 -1 (-2875 2000)(-2875 2050);
WIRE 17 -1 (-2875 2050)(-2875 2400);
WIRE 17 -1 (-2875 2400)(-2875 2450);
WIRE 17 -1 (-2875 2450)(-2875 2500);
WIRE 17 -1 (-2875 2500)(-2875 2550);
WIRE 17 -1 (-5600 2700)(-5600 2650);
WIRE 17 -1 (-5600 2750)(-5600 2700);
WIRE 17 -1 (-5600 2800)(-5600 2750);
WIRE 17 -1 (-5600 3200)(-5600 2800);
WIRE 17 -1 (-5600 3200)(-5600 3250);
WIRE 17 -1 (-6750 3600)(-5600 3600);
FORCEPROP 2 LAST SIG_NAME P3E_CPU1_PE3_MP_RXN<15:8>
J 0
(-6710 3610);
DISPLAY 0.617021 (-6710 3610);
PAINT ORANGE (-6710 3610);
WIRE 17 -1 (-5600 3400)(-5600 3600);
WIRE 17 -1 (-5600 3250)(-5600 3300);
WIRE 17 -1 (-5600 3300)(-5600 3400);
WIRE 17 -1 (-6750 3700)(-5450 3700);
FORCEPROP 2 LAST SIG_NAME P3E_CPU1_PE3_MP_RXP<15:8>
J 0
(-6710 3710);
DISPLAY 0.617021 (-6710 3710);
PAINT ORANGE (-6710 3710);
WIRE 17 -1 (-5450 2950)(-5450 2900);
WIRE 17 -1 (-5450 3000)(-5450 2950);
WIRE 17 -1 (-5450 3700)(-5450 3550);
WIRE 17 -1 (-5450 3550)(-5450 3500);
WIRE 17 -1 (-5450 3050)(-5450 3000);
WIRE 17 -1 (-5450 3150)(-5450 3050);
WIRE 17 -1 (-5450 3500)(-5450 3450);
WIRE 17 -1 (-5450 3450)(-5450 3150);
WIRE 17 -1 (-6850 1525)(-5600 1525);
FORCEPROP 2 LAST SIG_NAME P3E_CPU1_PE3_MP_RXN<7:0>
J 0
(-6810 1535);
DISPLAY 0.617021 (-6810 1535);
PAINT ORANGE (-6810 1535);
WIRE 17 -1 (-5600 1650)(-5600 1525);
WIRE 17 -1 (-5600 1700)(-5600 1650);
WIRE 17 -1 (-5600 1750)(-5600 1700);
WIRE 17 -1 (-5600 1800)(-5600 1750);
WIRE 17 -1 (-5600 2150)(-5600 1800);
WIRE 17 -1 (-5600 2200)(-5600 2150);
WIRE 17 -1 (-5600 2200)(-5600 2250);
WIRE 17 -1 (-5600 2250)(-5600 2300);
WIRE 17 -1 (-6850 1400)(-5450 1400);
FORCEPROP 2 LAST SIG_NAME P3E_CPU1_PE3_MP_RXP<7:0>
J 0
(-6810 1410);
DISPLAY 0.617021 (-6810 1410);
PAINT ORANGE (-6810 1410);
WIRE 17 -1 (-5450 1900)(-5450 1400);
WIRE 17 -1 (-5450 1950)(-5450 1900);
WIRE 17 -1 (-5450 2000)(-5450 1950);
WIRE 17 -1 (-5450 2000)(-5450 2050);
WIRE 17 -1 (-5450 2050)(-5450 2400);
WIRE 17 -1 (-5450 2450)(-5450 2400);
WIRE 17 -1 (-5450 2500)(-5450 2450);
WIRE 17 -1 (-5450 2550)(-5450 2500);
WIRE 16 -1 (-2825 3225)(-3375 3225);
WIRE 16 -1 (-5350 2925)(-4875 2925);
WIRE 16 -1 (-5350 3025)(-4875 3025);
WIRE 16 -1 (-5500 3225)(-4875 3225);
WIRE 16 -1 (-5350 2975)(-4875 2975);
WIRE 16 -1 (-5350 1875)(-4875 1875);
WIRE 16 -1 (-5350 1925)(-4875 1925);
WIRE 16 -1 (-5350 1975)(-4875 1975);
WIRE 16 -1 (-5350 2025)(-4875 2025);
WIRE 16 -1 (-4875 1625)(-5500 1625);
WIRE 16 -1 (-4875 1675)(-5500 1675);
WIRE 16 -1 (-4875 1725)(-5500 1725);
WIRE 16 -1 (-4875 1775)(-5500 1775);
WIRE 16 -1 (-4875 2375)(-5350 2375);
WIRE 16 -1 (-5350 2425)(-4875 2425);
WIRE 16 -1 (-5350 2475)(-4875 2475);
WIRE 16 -1 (-5350 2525)(-4875 2525);
WIRE 16 -1 (-5350 2875)(-4875 2875);
WIRE 16 -1 (-5500 3375)(-4875 3375);
WIRE 16 -1 (-5350 3425)(-4875 3425);
WIRE 16 -1 (-5350 3475)(-4875 3475);
WIRE 16 -1 (-5350 3525)(-4875 3525);
WIRE 16 -1 (-4875 2125)(-5500 2125);
WIRE 16 -1 (-5500 2175)(-4875 2175);
WIRE 16 -1 (-5500 2225)(-4875 2225);
WIRE 16 -1 (-5500 2275)(-4875 2275);
WIRE 16 -1 (-5500 2625)(-4875 2625);
WIRE 16 -1 (-5500 2675)(-4875 2675);
WIRE 16 -1 (-5500 2725)(-4875 2725);
WIRE 16 -1 (-5500 2775)(-4875 2775);
WIRE 16 -1 (-5350 3125)(-4875 3125);
WIRE 16 -1 (-5500 3175)(-4875 3175);
WIRE 16 -1 (-5500 3275)(-4875 3275);
WIRE 16 -1 (-3375 1875)(-2975 1875);
WIRE 16 -1 (-2975 1925)(-3375 1925);
WIRE 16 -1 (-3375 1975)(-2975 1975);
WIRE 16 -1 (-2975 2025)(-3375 2025);
WIRE 16 -1 (-2825 1625)(-3375 1625);
WIRE 16 -1 (-2825 1675)(-3375 1675);
WIRE 16 -1 (-2825 1725)(-3375 1725);
WIRE 16 -1 (-2825 1775)(-3375 1775);
WIRE 16 -1 (-2975 2375)(-3375 2375);
WIRE 16 -1 (-2975 2425)(-3375 2425);
WIRE 16 -1 (-2975 2475)(-3375 2475);
WIRE 16 -1 (-2975 2525)(-3375 2525);
WIRE 16 -1 (-2975 2875)(-3375 2875);
WIRE 16 -1 (-2975 2925)(-3375 2925);
WIRE 16 -1 (-2975 2975)(-3375 2975);
WIRE 16 -1 (-2975 3025)(-3375 3025);
WIRE 16 -1 (-2975 3375)(-3375 3375);
WIRE 16 -1 (-3375 3425)(-2975 3425);
WIRE 16 -1 (-3375 3475)(-2975 3475);
WIRE 16 -1 (-2975 3525)(-3375 3525);
WIRE 16 -1 (-2825 2125)(-3375 2125);
WIRE 16 -1 (-2825 2175)(-3375 2175);
WIRE 16 -1 (-3375 2225)(-2825 2225);
WIRE 16 -1 (-3375 2275)(-2825 2275);
WIRE 16 -1 (-2825 2625)(-3375 2625);
WIRE 16 -1 (-3375 2675)(-2825 2675);
WIRE 16 -1 (-2825 2725)(-3375 2725);
WIRE 16 -1 (-2825 2775)(-3375 2775);
WIRE 16 -1 (-3375 3125)(-2825 3125);
WIRE 16 -1 (-2825 3175)(-3375 3175);
WIRE 16 -1 (-2825 3275)(-3375 3275);
FORCENOTE
ROOM=CPU1
(-7925 350) 0;
DISPLAY LEFT (-7925 350);
DISPLAY 1.723404 (-7925 350);
PAINT PURPLE (-7925 350);
FORCENOTE
BOM_COST=PROC_SOCKET
(-7925 225) 0;
DISPLAY LEFT (-7925 225);
DISPLAY 1.723404 (-7925 225);
PAINT PURPLE (-7925 225);
FORCENOTE
DE NOTE:
(-7550 3400) 0;
DISPLAY LEFT (-7550 3400);
DISPLAY 1.021277 (-7550 3400);
PAINT PURPLE (-7550 3400);
FORCENOTE
POLARITY SWAPED P3E_CPU1_PE3_MP_RX*<12>
(-7550 3325) 0;
DISPLAY LEFT (-7550 3325);
DISPLAY 1.021277 (-7550 3325);
PAINT PURPLE (-7550 3325);
QUIT
